G04 ================== begin FILE IDENTIFICATION RECORD ==================*
G04 Layout Name:  15105-sa.brd*
G04 Film Name:    DP_REF_L3*
G04 File Format:  Gerber RS274X*
G04 File Origin:  Cadence Allegro 16.5-S056*
G04 Origin Date:  Wed Nov 16 02:02:37 2016*
G04 *
G04 Layer:  BOARD GEOMETRY/DP_REF_L3_TBL*
G04 Layer:  BOARD GEOMETRY/DP_REF_L3_L3*
G04 Layer:  BOARD GEOMETRY/PANEL_OUTLINE*
G04 *
G04 Offset:    (0.00 0.00)*
G04 Mirror:    No*
G04 Mode:      Positive*
G04 Rotation:  0*
G04 FullContactRelief:  No*
G04 UndefLineWidth:     6.00*
G04 ================== end FILE IDENTIFICATION RECORD ====================*
%FSLAX35Y35*MOIN*%
%IR0*IPPOS*OFA0.00000B0.00000*MIA0B0*SFA1.00000B1.00000*%
%ADD10C,.02*%
%ADD11C,.004*%
%ADD12C,.006*%
%ADD13C,.0055*%
G75*
%LPD*%
G75*
G54D10*
G01X1479970Y759338D02*
X2267470D01*
G01X1479970Y863288D02*
Y759338D01*
G01Y793988D02*
X2267470D01*
G01X1479970Y828638D02*
X2267470D01*
G01X1479970Y863288D02*
X2267470D01*
G01X1654970D02*
Y759338D01*
G01X1952470Y863288D02*
Y759338D01*
G01X2057470Y863288D02*
Y759338D01*
G01X2267470Y863288D02*
Y759338D01*
G54D11*
G01X86040Y214162D02*
X136398D01*
G01X86538Y215362D02*
X136896D01*
G01X75200Y225002D02*
X86040Y214162D01*
G01X76400Y225500D02*
X86538Y215362D01*
G01X75200Y227689D02*
Y225002D01*
G01X76400Y227689D02*
Y225500D01*
G01X86538Y215362D02*
X136896D01*
G01X86040Y214162D02*
X136398D01*
G01X76400Y225500D02*
X86538Y215362D01*
G01X75200Y225002D02*
X86040Y214162D01*
G01X76400Y227689D02*
Y225500D01*
G01X75200Y227689D02*
Y225002D01*
G01X91059Y228394D02*
Y224784D01*
G01X89859D02*
Y228892D01*
G01X91812Y229147D02*
X91059Y228394D01*
G01X89859Y228892D02*
X91314Y230347D01*
G01X94436Y229147D02*
X91812D01*
G01X91314Y230347D02*
X94934D01*
G01X105369Y218214D02*
X94436Y229147D01*
G01X94934Y230347D02*
X105867Y219414D01*
G01X94934Y230347D02*
X105867Y219414D01*
G01X105369Y218214D02*
X94436Y229147D01*
G01X91314Y230347D02*
X94934D01*
G01X94436Y229147D02*
X91812D01*
G01X89859Y228892D02*
X91314Y230347D01*
G01X91812Y229147D02*
X91059Y228394D01*
G01X89859Y224784D02*
Y228892D01*
G01X91059Y228394D02*
Y224784D01*
G01X141111Y218214D02*
X105369D01*
G01X105867Y219414D02*
X141609D01*
G01X105867D02*
X141609D01*
G01X141111Y218214D02*
X105369D01*
G01X136398Y214162D02*
X168880Y181680D01*
G01X136896Y215362D02*
X170080Y182178D01*
G01X136896Y215362D02*
X170080Y182178D01*
G01X136398Y214162D02*
X168880Y181680D01*
G01X180600Y178725D02*
X141111Y218214D01*
G01X141609Y219414D02*
X201500Y159523D01*
G01X141609Y219414D02*
X201500Y159523D01*
G01X141609Y219414D02*
X201500Y159523D01*
G01X141609Y219414D02*
X201500Y159523D01*
G01X141609Y219414D02*
X201500Y159523D01*
G01X141609Y219414D02*
X201500Y159523D01*
G01X141609Y219414D02*
X201500Y159523D01*
G01X141609Y219414D02*
X201500Y159523D01*
G01X141609Y219414D02*
X201500Y159523D01*
G01X141609Y219414D02*
X201500Y159523D01*
G01X180600Y178725D02*
X141111Y218214D01*
G01X194100Y130296D02*
X213700Y110696D01*
G01X195300Y130794D02*
X214900Y111194D01*
G01X194100Y153732D02*
Y130296D01*
G01X195300Y154230D02*
Y130794D01*
G01D02*
X214900Y111194D01*
G01X194100Y130296D02*
X213700Y110696D01*
G01X195300Y154230D02*
Y130794D01*
G01X194100Y153732D02*
Y130296D01*
G01X168880Y178952D02*
X194100Y153732D01*
G01X170080Y179450D02*
X195300Y154230D01*
G01X170080Y179450D02*
X195300Y154230D01*
G01X168880Y178952D02*
X194100Y153732D01*
G01X185267Y174058D02*
X184206D01*
G01X186115Y173210D02*
X185267Y174058D01*
G01X188024Y171301D02*
X186964D01*
G01X188873Y170452D02*
X188024Y171301D01*
G01X190782Y168543D02*
X189722D01*
G01X200300Y159025D02*
X190782Y168543D01*
G01X185267Y174058D02*
X184206D01*
G01X186115Y173210D02*
X185267Y174058D01*
G01X188024Y171301D02*
X186964D01*
G01X188873Y170452D02*
X188024Y171301D01*
G01X190782Y168543D02*
X189722D01*
G01X200300Y159025D02*
X190782Y168543D01*
G01X168880Y181680D02*
Y178952D01*
G01X170080Y182178D02*
Y179450D01*
G01Y182178D02*
Y179450D01*
G01X168880Y181680D02*
Y178952D01*
G01X182509Y176816D02*
X181448D01*
G01X183358Y175967D02*
X182509Y176816D01*
G01D02*
X181448D01*
G01X183358Y175967D02*
X182509Y176816D01*
G01X225389Y74987D02*
X238348D01*
G01X225887Y76187D02*
X238846D01*
G01X213700Y86676D02*
X225389Y74987D01*
G01X214900Y87174D02*
X225887Y76187D01*
G01X213700Y110696D02*
Y86676D01*
G01X214900Y111194D02*
Y87174D01*
G01X225887Y76187D02*
X238846D01*
G01X225389Y74987D02*
X238348D01*
G01X214900Y87174D02*
X225887Y76187D01*
G01X213700Y86676D02*
X225389Y74987D01*
G01X214900Y111194D02*
Y87174D01*
G01X213700Y110696D02*
Y86676D01*
G01X217884Y98293D02*
Y114318D01*
G01X219084Y114816D02*
Y98791D01*
G01X225677Y90500D02*
X217884Y98293D01*
G01X219084Y98791D02*
X226175Y91700D01*
G01X236147Y90500D02*
X225677D01*
G01X226175Y91700D02*
X236645D01*
G01X226175D02*
X236645D01*
G01X236147Y90500D02*
X225677D01*
G01X219084Y98791D02*
X226175Y91700D01*
G01X225677Y90500D02*
X217884Y98293D01*
G01X219084Y114816D02*
Y98791D01*
G01X217884Y98293D02*
Y114318D01*
G01X201500Y159523D02*
Y132400D01*
G01Y159523D02*
Y132400D01*
G01X200300Y131902D02*
Y145400D01*
G01X201500Y159523D02*
Y132400D01*
G01X217884Y114318D02*
X200300Y131902D01*
G01X201500Y132400D02*
X219084Y114816D01*
G01X201500Y132400D02*
X219084Y114816D01*
G01X217884Y114318D02*
X200300Y131902D01*
G01X201500Y159523D02*
Y132400D01*
G01X200300Y131902D02*
Y145400D01*
G01Y152000D02*
Y159025D01*
G01Y148100D02*
Y149300D01*
G01Y152000D02*
Y159025D01*
G01Y148100D02*
Y149300D01*
G01X242361Y70974D02*
Y68989D01*
G01X243561Y71472D02*
Y68989D01*
G01X238348Y74987D02*
X242361Y70974D01*
G01X238846Y76187D02*
X243561Y71472D01*
G01D02*
Y68989D01*
G01X242361Y70974D02*
Y68989D01*
G01X238846Y76187D02*
X243561Y71472D01*
G01X238348Y74987D02*
X242361Y70974D01*
G01X242347Y84300D02*
X236147Y90500D01*
G01X236645Y91700D02*
X243547Y84798D01*
G01X242347Y78989D02*
Y84300D01*
G01X243547Y84798D02*
Y78989D01*
G01Y84798D02*
Y78989D01*
G01X242347D02*
Y84300D01*
G01X236645Y91700D02*
X243547Y84798D01*
G01X242347Y84300D02*
X236147Y90500D01*
G54D12*
G01X-27072Y-83981D02*
Y-101481D01*
G01X-32094Y-83981D02*
X-22050D01*
G01X-13284Y-101481D02*
Y-83981D01*
G01Y-92439D02*
X-12192Y-90981D01*
X-11100Y-90106D01*
X-9354Y-89815D01*
X-8044Y-90106D01*
X-6515Y-91273D01*
X-5860Y-93023D01*
Y-101481D01*
G01X7928Y-89815D02*
Y-101481D01*
G01Y-85148D02*
X7491Y-84856D01*
Y-84273D01*
X7928Y-83981D01*
X8365Y-84273D01*
Y-84856D01*
X7928Y-85148D01*
G01X22153Y-99440D02*
X23245Y-100606D01*
X24773Y-101481D01*
X26083D01*
X27393Y-100898D01*
X28266Y-100023D01*
X28703Y-98857D01*
X28485Y-97106D01*
X27611Y-96231D01*
X23681Y-94481D01*
X22808Y-92439D01*
X23245Y-90981D01*
X24118Y-90106D01*
X25428Y-89815D01*
X26738Y-90106D01*
X28048Y-90981D01*
G01X57371Y-105856D02*
X58900Y-107023D01*
X60646Y-107314D01*
X62174Y-107023D01*
X63485Y-105565D01*
X64358Y-103523D01*
Y-89815D01*
G01Y-92148D02*
X63485Y-90981D01*
X62174Y-90106D01*
X60646Y-89815D01*
X58900Y-90398D01*
X57808Y-91564D01*
X56934Y-93606D01*
X56498Y-95648D01*
X56716Y-97398D01*
X57590Y-99440D01*
X58900Y-100898D01*
X60646Y-101481D01*
X61956Y-101189D01*
X63485Y-100023D01*
X64358Y-98857D01*
G01X74653Y-93606D02*
X81640D01*
X80985Y-91564D01*
X79893Y-90398D01*
X78365Y-89815D01*
X76836Y-90106D01*
X75526Y-90981D01*
X74653Y-93023D01*
X74216Y-94773D01*
Y-96523D01*
X74653Y-98273D01*
X75745Y-100023D01*
X77055Y-101189D01*
X78583Y-101481D01*
X80111Y-100898D01*
X81640Y-99148D01*
G01X92371Y-101481D02*
Y-89815D01*
G01Y-92148D02*
X93463Y-90981D01*
X94555Y-90106D01*
X96083Y-89815D01*
X97174Y-90106D01*
X98485Y-90981D01*
G01X108998Y-101481D02*
Y-83981D01*
G01Y-92731D02*
X110090Y-90981D01*
X111400Y-90106D01*
X112710Y-89815D01*
X114674Y-90398D01*
X115985Y-91564D01*
X116858Y-93606D01*
Y-95939D01*
X116421Y-98273D01*
X115548Y-100023D01*
X114020Y-101189D01*
X112710Y-101481D01*
X111400Y-101189D01*
X110090Y-100315D01*
X108998Y-98857D01*
G01X127153Y-93606D02*
X134140D01*
X133485Y-91564D01*
X132393Y-90398D01*
X130865Y-89815D01*
X129336Y-90106D01*
X128026Y-90981D01*
X127153Y-93023D01*
X126716Y-94773D01*
Y-96523D01*
X127153Y-98273D01*
X128245Y-100023D01*
X129555Y-101189D01*
X131083Y-101481D01*
X132611Y-100898D01*
X134140Y-99148D01*
G01X144871Y-101481D02*
Y-89815D01*
G01Y-92148D02*
X145963Y-90981D01*
X147055Y-90106D01*
X148583Y-89815D01*
X149674Y-90106D01*
X150985Y-90981D01*
G01X182928Y-89815D02*
Y-101481D01*
G01Y-85148D02*
X182491Y-84856D01*
Y-84273D01*
X182928Y-83981D01*
X183365Y-84273D01*
Y-84856D01*
X182928Y-85148D01*
G01X197153Y-99440D02*
X198245Y-100606D01*
X199773Y-101481D01*
X201083D01*
X202393Y-100898D01*
X203266Y-100023D01*
X203703Y-98857D01*
X203485Y-97106D01*
X202611Y-96231D01*
X198681Y-94481D01*
X197808Y-92439D01*
X198245Y-90981D01*
X199118Y-90106D01*
X200428Y-89815D01*
X201738Y-90106D01*
X203048Y-90981D01*
G01X231934Y-105856D02*
X233463Y-107023D01*
X234773Y-107314D01*
X236520Y-106731D01*
X237830Y-105273D01*
X238485Y-102647D01*
Y-89815D01*
G01Y-85148D02*
X238048Y-84856D01*
Y-84273D01*
X238485Y-83981D01*
X238921Y-84273D01*
Y-84856D01*
X238485Y-85148D01*
G01X249216Y-89815D02*
Y-97981D01*
X250090Y-100023D01*
X251400Y-101189D01*
X252928Y-101481D01*
X254456Y-101189D01*
X255766Y-100023D01*
X256640Y-97981D01*
G01Y-101481D02*
Y-89815D01*
G01X267153Y-99440D02*
X268245Y-100606D01*
X269773Y-101481D01*
X271083D01*
X272393Y-100898D01*
X273266Y-100023D01*
X273703Y-98857D01*
X273485Y-97106D01*
X272611Y-96231D01*
X268681Y-94481D01*
X267808Y-92439D01*
X268245Y-90981D01*
X269118Y-90106D01*
X270428Y-89815D01*
X271738Y-90106D01*
X273048Y-90981D01*
G01X287928Y-83981D02*
Y-101481D01*
G01X284871Y-89815D02*
X290985D01*
G01X321618Y-101481D02*
Y-86606D01*
X322055Y-85148D01*
X322928Y-84273D01*
X324238Y-83981D01*
X325548Y-84564D01*
X326203Y-86023D01*
G01X323583Y-90981D02*
X319216D01*
G01X340428Y-101481D02*
X339118Y-101189D01*
X337808Y-100023D01*
X336934Y-97981D01*
X336498Y-95648D01*
X336934Y-93314D01*
X337808Y-91273D01*
X339118Y-90106D01*
X340428Y-89815D01*
X341738Y-90106D01*
X343048Y-91273D01*
X343921Y-93314D01*
X344140Y-95648D01*
X343921Y-97981D01*
X343048Y-100023D01*
X341738Y-101189D01*
X340428Y-101481D01*
G01X354871D02*
Y-89815D01*
G01Y-92148D02*
X355963Y-90981D01*
X357055Y-90106D01*
X358583Y-89815D01*
X359674Y-90106D01*
X360985Y-90981D01*
G01X388343Y-106731D02*
X389653Y-107314D01*
X391400Y-106731D01*
X392491Y-105565D01*
X393365Y-104106D01*
X394674Y-99440D01*
X397513Y-89815D01*
G01X390526D02*
X394674Y-99440D01*
G01X410428Y-101481D02*
X409118Y-101189D01*
X407808Y-100023D01*
X406934Y-97981D01*
X406498Y-95648D01*
X406934Y-93314D01*
X407808Y-91273D01*
X409118Y-90106D01*
X410428Y-89815D01*
X411738Y-90106D01*
X413048Y-91273D01*
X413921Y-93314D01*
X414140Y-95648D01*
X413921Y-97981D01*
X413048Y-100023D01*
X411738Y-101189D01*
X410428Y-101481D01*
G01X424216Y-89815D02*
Y-97981D01*
X425090Y-100023D01*
X426400Y-101189D01*
X427928Y-101481D01*
X429456Y-101189D01*
X430766Y-100023D01*
X431640Y-97981D01*
G01Y-101481D02*
Y-89815D01*
G01X442371Y-101481D02*
Y-89815D01*
G01Y-92148D02*
X443463Y-90981D01*
X444555Y-90106D01*
X446083Y-89815D01*
X447174Y-90106D01*
X448485Y-90981D01*
G01X477371Y-101481D02*
Y-89815D01*
G01Y-92148D02*
X478463Y-90981D01*
X479555Y-90106D01*
X481083Y-89815D01*
X482174Y-90106D01*
X483485Y-90981D01*
G01X494653Y-93606D02*
X501640D01*
X500985Y-91564D01*
X499893Y-90398D01*
X498365Y-89815D01*
X496836Y-90106D01*
X495526Y-90981D01*
X494653Y-93023D01*
X494216Y-94773D01*
Y-96523D01*
X494653Y-98273D01*
X495745Y-100023D01*
X497055Y-101189D01*
X498583Y-101481D01*
X500111Y-100898D01*
X501640Y-99148D01*
G01X514118Y-101481D02*
Y-86606D01*
X514555Y-85148D01*
X515428Y-84273D01*
X516738Y-83981D01*
X518048Y-84564D01*
X518703Y-86023D01*
G01X516083Y-90981D02*
X511716D01*
G01X529653Y-93606D02*
X536640D01*
X535985Y-91564D01*
X534893Y-90398D01*
X533365Y-89815D01*
X531836Y-90106D01*
X530526Y-90981D01*
X529653Y-93023D01*
X529216Y-94773D01*
Y-96523D01*
X529653Y-98273D01*
X530745Y-100023D01*
X532055Y-101189D01*
X533583Y-101481D01*
X535111Y-100898D01*
X536640Y-99148D01*
G01X547371Y-101481D02*
Y-89815D01*
G01Y-92148D02*
X548463Y-90981D01*
X549555Y-90106D01*
X551083Y-89815D01*
X552174Y-90106D01*
X553485Y-90981D01*
G01X564653Y-93606D02*
X571640D01*
X570985Y-91564D01*
X569893Y-90398D01*
X568365Y-89815D01*
X566836Y-90106D01*
X565526Y-90981D01*
X564653Y-93023D01*
X564216Y-94773D01*
Y-96523D01*
X564653Y-98273D01*
X565745Y-100023D01*
X567055Y-101189D01*
X568583Y-101481D01*
X570111Y-100898D01*
X571640Y-99148D01*
G01X581716Y-101481D02*
Y-89815D01*
G01Y-92731D02*
X582590Y-91273D01*
X583900Y-90106D01*
X585646Y-89815D01*
X587174Y-90106D01*
X588485Y-91273D01*
X589140Y-93314D01*
Y-101481D01*
G01X606421Y-91273D02*
X604893Y-90106D01*
X603583Y-89815D01*
X601836Y-90398D01*
X600526Y-91564D01*
X599653Y-93606D01*
X599434Y-95648D01*
X599653Y-97690D01*
X600526Y-99440D01*
X601836Y-100898D01*
X603583Y-101481D01*
X605111Y-100898D01*
X606421Y-99731D01*
G01X617153Y-93606D02*
X624140D01*
X623485Y-91564D01*
X622393Y-90398D01*
X620865Y-89815D01*
X619336Y-90106D01*
X618026Y-90981D01*
X617153Y-93023D01*
X616716Y-94773D01*
Y-96523D01*
X617153Y-98273D01*
X618245Y-100023D01*
X619555Y-101189D01*
X621083Y-101481D01*
X622611Y-100898D01*
X624140Y-99148D01*
G01X655428Y-83981D02*
Y-101481D01*
G01X652371Y-89815D02*
X658485D01*
G01X672928Y-101481D02*
X671618Y-101189D01*
X670308Y-100023D01*
X669434Y-97981D01*
X668998Y-95648D01*
X669434Y-93314D01*
X670308Y-91273D01*
X671618Y-90106D01*
X672928Y-89815D01*
X674238Y-90106D01*
X675548Y-91273D01*
X676421Y-93314D01*
X676640Y-95648D01*
X676421Y-97981D01*
X675548Y-100023D01*
X674238Y-101189D01*
X672928Y-101481D01*
G01X706618D02*
Y-86606D01*
X707055Y-85148D01*
X707928Y-84273D01*
X709238Y-83981D01*
X710548Y-84564D01*
X711203Y-86023D01*
G01X708583Y-90981D02*
X704216D01*
G01X725428Y-89815D02*
Y-101481D01*
G01Y-85148D02*
X724991Y-84856D01*
Y-84273D01*
X725428Y-83981D01*
X725865Y-84273D01*
Y-84856D01*
X725428Y-85148D01*
G01X739216Y-101481D02*
Y-89815D01*
G01Y-92731D02*
X740090Y-91273D01*
X741400Y-90106D01*
X743146Y-89815D01*
X744674Y-90106D01*
X745985Y-91273D01*
X746640Y-93314D01*
Y-101481D01*
G01X764358Y-83981D02*
Y-101481D01*
G01Y-98857D02*
X763485Y-100315D01*
X762174Y-101189D01*
X760646Y-101481D01*
X758900Y-100898D01*
X757590Y-99440D01*
X756716Y-97690D01*
X756498Y-95648D01*
X756716Y-93606D01*
X757590Y-91856D01*
X758900Y-90398D01*
X760646Y-89815D01*
X762174Y-90106D01*
X763266Y-90690D01*
X764358Y-91856D01*
G01X795428Y-83981D02*
Y-101481D01*
G01X792371Y-89815D02*
X798485D01*
G01X809216Y-101481D02*
Y-83981D01*
G01Y-92439D02*
X810308Y-90981D01*
X811400Y-90106D01*
X813146Y-89815D01*
X814456Y-90106D01*
X815985Y-91273D01*
X816640Y-93023D01*
Y-101481D01*
G01X827153Y-93606D02*
X834140D01*
X833485Y-91564D01*
X832393Y-90398D01*
X830865Y-89815D01*
X829336Y-90106D01*
X828026Y-90981D01*
X827153Y-93023D01*
X826716Y-94773D01*
Y-96523D01*
X827153Y-98273D01*
X828245Y-100023D01*
X829555Y-101189D01*
X831083Y-101481D01*
X832611Y-100898D01*
X834140Y-99148D01*
G01X860625Y-101481D02*
Y-83981D01*
X864991D01*
X866738Y-84856D01*
X868048Y-86023D01*
X869140Y-87772D01*
X870013Y-89815D01*
X870231Y-92731D01*
X870013Y-95648D01*
X869140Y-97690D01*
X868048Y-99440D01*
X866738Y-100606D01*
X864991Y-101481D01*
X860625D01*
G01X878561D02*
Y-83981D01*
X883801D01*
X885548Y-84856D01*
X886858Y-86898D01*
X887295Y-89231D01*
X886858Y-91564D01*
X885766Y-93314D01*
X883801Y-94190D01*
X878561D01*
G01X917928Y-89815D02*
Y-101481D01*
G01Y-85148D02*
X917491Y-84856D01*
Y-84273D01*
X917928Y-83981D01*
X918365Y-84273D01*
Y-84856D01*
X917928Y-85148D01*
G01X928878Y-101481D02*
Y-89815D01*
G01Y-93023D02*
X929533Y-91564D01*
X930625Y-90398D01*
X932153Y-89815D01*
X933681Y-90398D01*
X934773Y-91564D01*
X935428Y-93023D01*
Y-101481D01*
G01Y-93023D02*
X936083Y-91564D01*
X937174Y-90398D01*
X938703Y-89815D01*
X940231Y-90398D01*
X941323Y-91564D01*
X941978Y-93314D01*
Y-101481D01*
G01X948998Y-107314D02*
Y-89815D01*
G01Y-92439D02*
X950090Y-90981D01*
X951181Y-90106D01*
X952928Y-89815D01*
X954456Y-90106D01*
X955985Y-91564D01*
X956640Y-93606D01*
X956858Y-95648D01*
X956640Y-97690D01*
X955985Y-99731D01*
X954674Y-100898D01*
X952928Y-101481D01*
X951400Y-101189D01*
X949871Y-100315D01*
X948998Y-99148D01*
G01X967153Y-93606D02*
X974140D01*
X973485Y-91564D01*
X972393Y-90398D01*
X970865Y-89815D01*
X969336Y-90106D01*
X968026Y-90981D01*
X967153Y-93023D01*
X966716Y-94773D01*
Y-96523D01*
X967153Y-98273D01*
X968245Y-100023D01*
X969555Y-101189D01*
X971083Y-101481D01*
X972611Y-100898D01*
X974140Y-99148D01*
G01X991858Y-83981D02*
Y-101481D01*
G01Y-98857D02*
X990985Y-100315D01*
X989674Y-101189D01*
X988146Y-101481D01*
X986400Y-100898D01*
X985090Y-99440D01*
X984216Y-97690D01*
X983998Y-95648D01*
X984216Y-93606D01*
X985090Y-91856D01*
X986400Y-90398D01*
X988146Y-89815D01*
X989674Y-90106D01*
X990766Y-90690D01*
X991858Y-91856D01*
G01X1009358Y-101481D02*
Y-89815D01*
G01Y-91856D02*
X1008485Y-90690D01*
X1007174Y-90106D01*
X1005646Y-89815D01*
X1004118Y-90398D01*
X1002808Y-91564D01*
X1001934Y-93314D01*
X1001498Y-95648D01*
X1001934Y-97981D01*
X1002808Y-99731D01*
X1004118Y-100898D01*
X1005646Y-101481D01*
X1007174Y-101189D01*
X1008485Y-100315D01*
X1009358Y-99148D01*
G01X1019216Y-101481D02*
Y-89815D01*
G01Y-92731D02*
X1020090Y-91273D01*
X1021400Y-90106D01*
X1023146Y-89815D01*
X1024674Y-90106D01*
X1025985Y-91273D01*
X1026640Y-93314D01*
Y-101481D01*
G01X1043921Y-91273D02*
X1042393Y-90106D01*
X1041083Y-89815D01*
X1039336Y-90398D01*
X1038026Y-91564D01*
X1037153Y-93606D01*
X1036934Y-95648D01*
X1037153Y-97690D01*
X1038026Y-99440D01*
X1039336Y-100898D01*
X1041083Y-101481D01*
X1042611Y-100898D01*
X1043921Y-99731D01*
G01X1054653Y-93606D02*
X1061640D01*
X1060985Y-91564D01*
X1059893Y-90398D01*
X1058365Y-89815D01*
X1056836Y-90106D01*
X1055526Y-90981D01*
X1054653Y-93023D01*
X1054216Y-94773D01*
Y-96523D01*
X1054653Y-98273D01*
X1055745Y-100023D01*
X1057055Y-101189D01*
X1058583Y-101481D01*
X1060111Y-100898D01*
X1061640Y-99148D01*
G01X1092928Y-83981D02*
Y-101481D01*
G01X1089871Y-89815D02*
X1095985D01*
G01X1107371Y-101481D02*
Y-89815D01*
G01Y-92148D02*
X1108463Y-90981D01*
X1109555Y-90106D01*
X1111083Y-89815D01*
X1112174Y-90106D01*
X1113485Y-90981D01*
G01X1131858Y-101481D02*
Y-89815D01*
G01Y-91856D02*
X1130985Y-90690D01*
X1129674Y-90106D01*
X1128146Y-89815D01*
X1126618Y-90398D01*
X1125308Y-91564D01*
X1124434Y-93314D01*
X1123998Y-95648D01*
X1124434Y-97981D01*
X1125308Y-99731D01*
X1126618Y-100898D01*
X1128146Y-101481D01*
X1129674Y-101189D01*
X1130985Y-100315D01*
X1131858Y-99148D01*
G01X1148921Y-91273D02*
X1147393Y-90106D01*
X1146083Y-89815D01*
X1144336Y-90398D01*
X1143026Y-91564D01*
X1142153Y-93606D01*
X1141934Y-95648D01*
X1142153Y-97690D01*
X1143026Y-99440D01*
X1144336Y-100898D01*
X1146083Y-101481D01*
X1147611Y-100898D01*
X1148921Y-99731D01*
G01X1159653Y-93606D02*
X1166640D01*
X1165985Y-91564D01*
X1164893Y-90398D01*
X1163365Y-89815D01*
X1161836Y-90106D01*
X1160526Y-90981D01*
X1159653Y-93023D01*
X1159216Y-94773D01*
Y-96523D01*
X1159653Y-98273D01*
X1160745Y-100023D01*
X1162055Y-101189D01*
X1163583Y-101481D01*
X1165111Y-100898D01*
X1166640Y-99148D01*
G01X1177153Y-99440D02*
X1178245Y-100606D01*
X1179773Y-101481D01*
X1181083D01*
X1182393Y-100898D01*
X1183266Y-100023D01*
X1183703Y-98857D01*
X1183485Y-97106D01*
X1182611Y-96231D01*
X1178681Y-94481D01*
X1177808Y-92439D01*
X1178245Y-90981D01*
X1179118Y-90106D01*
X1180428Y-89815D01*
X1181738Y-90106D01*
X1183048Y-90981D01*
G01X1215428Y-89815D02*
Y-101481D01*
G01Y-85148D02*
X1214991Y-84856D01*
Y-84273D01*
X1215428Y-83981D01*
X1215865Y-84273D01*
Y-84856D01*
X1215428Y-85148D01*
G01X1229216Y-101481D02*
Y-89815D01*
G01Y-92731D02*
X1230090Y-91273D01*
X1231400Y-90106D01*
X1233146Y-89815D01*
X1234674Y-90106D01*
X1235985Y-91273D01*
X1236640Y-93314D01*
Y-101481D01*
G01X1267928D02*
Y-83981D01*
G01X1289358Y-101481D02*
Y-89815D01*
G01Y-91856D02*
X1288485Y-90690D01*
X1287174Y-90106D01*
X1285646Y-89815D01*
X1284118Y-90398D01*
X1282808Y-91564D01*
X1281934Y-93314D01*
X1281498Y-95648D01*
X1281934Y-97981D01*
X1282808Y-99731D01*
X1284118Y-100898D01*
X1285646Y-101481D01*
X1287174Y-101189D01*
X1288485Y-100315D01*
X1289358Y-99148D01*
G01X1298343Y-106731D02*
X1299653Y-107314D01*
X1301400Y-106731D01*
X1302491Y-105565D01*
X1303365Y-104106D01*
X1304674Y-99440D01*
X1307513Y-89815D01*
G01X1300526D02*
X1304674Y-99440D01*
G01X1317153Y-93606D02*
X1324140D01*
X1323485Y-91564D01*
X1322393Y-90398D01*
X1320865Y-89815D01*
X1319336Y-90106D01*
X1318026Y-90981D01*
X1317153Y-93023D01*
X1316716Y-94773D01*
Y-96523D01*
X1317153Y-98273D01*
X1318245Y-100023D01*
X1319555Y-101189D01*
X1321083Y-101481D01*
X1322611Y-100898D01*
X1324140Y-99148D01*
G01X1334871Y-101481D02*
Y-89815D01*
G01Y-92148D02*
X1335963Y-90981D01*
X1337055Y-90106D01*
X1338583Y-89815D01*
X1339674Y-90106D01*
X1340985Y-90981D01*
G01X1368561Y-83981D02*
Y-101481D01*
X1377295D01*
G01X1385625Y-97981D02*
X1386934Y-100023D01*
X1388681Y-101189D01*
X1390646Y-101481D01*
X1392393Y-101189D01*
X1394140Y-99731D01*
X1395231Y-97981D01*
X1395450Y-96231D01*
X1395013Y-94190D01*
X1393485Y-92731D01*
X1391956Y-92148D01*
X1389991D01*
G01X1391956D02*
X1393266Y-91273D01*
X1394358Y-89815D01*
X1394795Y-88065D01*
X1394358Y-86314D01*
X1393266Y-84856D01*
X1391301Y-83981D01*
X1389336Y-84273D01*
X1387371Y-85440D01*
G01X1407928Y-102064D02*
X1407491Y-101773D01*
Y-101189D01*
X1407928Y-100898D01*
X1408365Y-101189D01*
Y-101773D01*
X1407928Y-102064D01*
G01X1481717Y873038D02*
Y890538D01*
X1486083D01*
X1487830Y889663D01*
X1489140Y888496D01*
X1490232Y886747D01*
X1491105Y884704D01*
X1491323Y881788D01*
X1491105Y878871D01*
X1490232Y876829D01*
X1489140Y875079D01*
X1487830Y873913D01*
X1486083Y873038D01*
X1481717D01*
G01X1499653D02*
Y890538D01*
X1504893D01*
X1506640Y889663D01*
X1507950Y887621D01*
X1508387Y885288D01*
X1507950Y882955D01*
X1506858Y881205D01*
X1504893Y880329D01*
X1499653D01*
G01X1536400Y890538D02*
X1541640D01*
G01X1539020D02*
Y873038D01*
G01X1536400D02*
X1541640D01*
G01X1550843D02*
Y890538D01*
X1556520Y875955D01*
X1562197Y890538D01*
Y873038D01*
G01X1569653D02*
Y890538D01*
X1574893D01*
X1576640Y889663D01*
X1577950Y887621D01*
X1578387Y885288D01*
X1577950Y882955D01*
X1576858Y881205D01*
X1574893Y880329D01*
X1569653D01*
G01X1595887Y873038D02*
X1587153D01*
Y890538D01*
X1595887D01*
G01X1592393Y882080D02*
X1587153D01*
G01X1604217Y873038D02*
Y890538D01*
X1608583D01*
X1610330Y889663D01*
X1611640Y888496D01*
X1612732Y886747D01*
X1613605Y884704D01*
X1613823Y881788D01*
X1613605Y878871D01*
X1612732Y876829D01*
X1611640Y875079D01*
X1610330Y873913D01*
X1608583Y873038D01*
X1604217D01*
G01X1621061D02*
X1626520Y890538D01*
X1631979Y873038D01*
G01X1630013Y879163D02*
X1623026D01*
G01X1638998Y873038D02*
Y890538D01*
X1649042Y873038D01*
Y890538D01*
G01X1666323Y889079D02*
X1665013Y889955D01*
X1663485Y890538D01*
X1661738D01*
X1659773Y889663D01*
X1658245Y888205D01*
X1657153Y886454D01*
X1656280Y883538D01*
X1656061Y880913D01*
X1656498Y878288D01*
X1657153Y876538D01*
X1658463Y874788D01*
X1659992Y873621D01*
X1661520Y873038D01*
X1663048D01*
X1664577Y873621D01*
X1665887Y874496D01*
X1666979Y875662D01*
G01X1683387Y873038D02*
X1674653D01*
Y890538D01*
X1683387D01*
G01X1679893Y882080D02*
X1674653D01*
G01X1714020Y890538D02*
Y873038D01*
G01X1708998Y890538D02*
X1719042D01*
G01X1726061Y873038D02*
X1731520Y890538D01*
X1736979Y873038D01*
G01X1735013Y879163D02*
X1728026D01*
G01X1750766Y882371D02*
X1751640Y883246D01*
X1752295Y884704D01*
X1752732Y886747D01*
X1752295Y888496D01*
X1751422Y889663D01*
X1749893Y890538D01*
X1743998D01*
Y873038D01*
X1751203D01*
X1752732Y874204D01*
X1753605Y875955D01*
X1754042Y877996D01*
X1753605Y880038D01*
X1752295Y881788D01*
X1750766Y882371D01*
X1743998D01*
G01X1762153Y890538D02*
Y873038D01*
X1770887D01*
G01X1788387D02*
X1779653D01*
Y890538D01*
X1788387D01*
G01X1784893Y882080D02*
X1779653D01*
G01X1801520Y872455D02*
X1801083Y872746D01*
Y873330D01*
X1801520Y873621D01*
X1801957Y873330D01*
Y872746D01*
X1801520Y872455D01*
G01Y880329D02*
X1801083Y880621D01*
Y881205D01*
X1801520Y881496D01*
X1801957Y881205D01*
Y880621D01*
X1801520Y880329D01*
G01X1832153Y890538D02*
Y873038D01*
X1840887D01*
G01X1849217Y876538D02*
X1850526Y874496D01*
X1852273Y873330D01*
X1854238Y873038D01*
X1855985Y873330D01*
X1857732Y874788D01*
X1858823Y876538D01*
X1859042Y878288D01*
X1858605Y880329D01*
X1857077Y881788D01*
X1855548Y882371D01*
X1853583D01*
G01X1855548D02*
X1856858Y883246D01*
X1857950Y884704D01*
X1858387Y886454D01*
X1857950Y888205D01*
X1856858Y889663D01*
X1854893Y890538D01*
X1852928Y890246D01*
X1850963Y889079D01*
G01X1503600Y855888D02*
X1508840D01*
G01X1506220D02*
Y838388D01*
G01X1503600D02*
X1508840D01*
G01X1518043D02*
Y855888D01*
X1523720Y841305D01*
X1529397Y855888D01*
Y838388D01*
G01X1536853D02*
Y855888D01*
X1542093D01*
X1543840Y855013D01*
X1545150Y852971D01*
X1545587Y850638D01*
X1545150Y848305D01*
X1544058Y846555D01*
X1542093Y845679D01*
X1536853D01*
G01X1557628Y832555D02*
X1555445Y835471D01*
X1554353Y838388D01*
Y850054D01*
X1555445Y852971D01*
X1557628Y855888D01*
G01X1576220Y838388D02*
X1574473Y838680D01*
X1572945Y839846D01*
X1571635Y841596D01*
X1570761Y843638D01*
X1570325Y845971D01*
Y848305D01*
X1570761Y850638D01*
X1571635Y852680D01*
X1572945Y854429D01*
X1574473Y855596D01*
X1576220Y855888D01*
X1577966Y855596D01*
X1579495Y854429D01*
X1580805Y852680D01*
X1581679Y850638D01*
X1582115Y848305D01*
Y845971D01*
X1581679Y843638D01*
X1580805Y841596D01*
X1579495Y839846D01*
X1577966Y838680D01*
X1576220Y838388D01*
G01X1590008D02*
Y855888D01*
G01Y847430D02*
X1591100Y848888D01*
X1592192Y849763D01*
X1593938Y850054D01*
X1595248Y849763D01*
X1596777Y848596D01*
X1597432Y846846D01*
Y838388D01*
G01X1604670D02*
Y850054D01*
G01Y846846D02*
X1605325Y848305D01*
X1606417Y849471D01*
X1607945Y850054D01*
X1609473Y849471D01*
X1610565Y848305D01*
X1611220Y846846D01*
Y838388D01*
G01Y846846D02*
X1611875Y848305D01*
X1612966Y849471D01*
X1614495Y850054D01*
X1616023Y849471D01*
X1617115Y848305D01*
X1617770Y846555D01*
Y838388D01*
G01X1629812Y832555D02*
X1631995Y835471D01*
X1633087Y838388D01*
Y850054D01*
X1631995Y852971D01*
X1629812Y855888D01*
G01X1532470Y769088D02*
Y786588D01*
X1529850Y783088D01*
G01Y769088D02*
X1535090D01*
G01X1549970Y786588D02*
X1548223Y786005D01*
X1546913Y784546D01*
X1546040Y782797D01*
X1545385Y780463D01*
X1545167Y777838D01*
X1545385Y775213D01*
X1546040Y772879D01*
X1546913Y771129D01*
X1548223Y769671D01*
X1549970Y769088D01*
X1551716Y769671D01*
X1553027Y771129D01*
X1553900Y772879D01*
X1554555Y775213D01*
X1554773Y777838D01*
X1554555Y780463D01*
X1553900Y782797D01*
X1553027Y784546D01*
X1551716Y786005D01*
X1549970Y786588D01*
G01X1567470D02*
X1565723Y786005D01*
X1564413Y784546D01*
X1563540Y782797D01*
X1562885Y780463D01*
X1562667Y777838D01*
X1562885Y775213D01*
X1563540Y772879D01*
X1564413Y771129D01*
X1565723Y769671D01*
X1567470Y769088D01*
X1569216Y769671D01*
X1570527Y771129D01*
X1571400Y772879D01*
X1572055Y775213D01*
X1572273Y777838D01*
X1572055Y780463D01*
X1571400Y782797D01*
X1570527Y784546D01*
X1569216Y786005D01*
X1567470Y786588D01*
G01X1584970Y768505D02*
X1584533Y768796D01*
Y769380D01*
X1584970Y769671D01*
X1585407Y769380D01*
Y768796D01*
X1584970Y768505D01*
G01X1602470Y786588D02*
X1600723Y786005D01*
X1599413Y784546D01*
X1598540Y782797D01*
X1597885Y780463D01*
X1597667Y777838D01*
X1597885Y775213D01*
X1598540Y772879D01*
X1599413Y771129D01*
X1600723Y769671D01*
X1602470Y769088D01*
X1604216Y769671D01*
X1605527Y771129D01*
X1606400Y772879D01*
X1607055Y775213D01*
X1607273Y777838D01*
X1607055Y780463D01*
X1606400Y782797D01*
X1605527Y784546D01*
X1604216Y786005D01*
X1602470Y786588D01*
G01X1541220Y803738D02*
X1542748Y804030D01*
X1544495Y804904D01*
X1545587Y806362D01*
X1546023Y808405D01*
X1545587Y810446D01*
X1544277Y812196D01*
X1542312Y813071D01*
X1540128D01*
X1538818Y813655D01*
X1537726Y815113D01*
X1537290Y817154D01*
X1537945Y819196D01*
X1539473Y820655D01*
X1541220Y821238D01*
X1542966Y820655D01*
X1544495Y819196D01*
X1545150Y817154D01*
X1544713Y815113D01*
X1543622Y813655D01*
X1542312Y813071D01*
X1540128D01*
X1538163Y812196D01*
X1536853Y810446D01*
X1536417Y808405D01*
X1536853Y806362D01*
X1537945Y804904D01*
X1539692Y804030D01*
X1541220Y803738D01*
G01X1553917Y806362D02*
X1555226Y804904D01*
X1556755Y804030D01*
X1558720Y803738D01*
X1560685Y804321D01*
X1562213Y805488D01*
X1563305Y807529D01*
X1563523Y809863D01*
X1563087Y812196D01*
X1561995Y813655D01*
X1560466Y814821D01*
X1558938Y815113D01*
X1557410Y814821D01*
X1555445Y813655D01*
X1556100Y821238D01*
X1561995D01*
G01X1576220Y803155D02*
X1575783Y803446D01*
Y804030D01*
X1576220Y804321D01*
X1576657Y804030D01*
Y803446D01*
X1576220Y803155D01*
G01X1593720Y821238D02*
X1591973Y820655D01*
X1590663Y819196D01*
X1589790Y817447D01*
X1589135Y815113D01*
X1588917Y812488D01*
X1589135Y809863D01*
X1589790Y807529D01*
X1590663Y805779D01*
X1591973Y804321D01*
X1593720Y803738D01*
X1595466Y804321D01*
X1596777Y805779D01*
X1597650Y807529D01*
X1598305Y809863D01*
X1598523Y812488D01*
X1598305Y815113D01*
X1597650Y817447D01*
X1596777Y819196D01*
X1595466Y820655D01*
X1593720Y821238D01*
G01X1709670Y855888D02*
X1712726Y838388D01*
X1716220Y855888D01*
X1719713Y838388D01*
X1722770Y855888D01*
G01X1731100D02*
X1736340D01*
G01X1733720D02*
Y838388D01*
G01X1731100D02*
X1736340D01*
G01X1746417D02*
Y855888D01*
X1750783D01*
X1752530Y855013D01*
X1753840Y853846D01*
X1754932Y852097D01*
X1755805Y850054D01*
X1756023Y847138D01*
X1755805Y844221D01*
X1754932Y842179D01*
X1753840Y840429D01*
X1752530Y839263D01*
X1750783Y838388D01*
X1746417D01*
G01X1768720Y855888D02*
Y838388D01*
G01X1763698Y855888D02*
X1773742D01*
G01X1781635Y838388D02*
Y855888D01*
G01X1790805D02*
Y838388D01*
G01Y847138D02*
X1781635D01*
G01X1802628Y832555D02*
X1800445Y835471D01*
X1799353Y838388D01*
Y850054D01*
X1800445Y852971D01*
X1802628Y855888D01*
G01X1814670Y838388D02*
Y850054D01*
G01Y846846D02*
X1815325Y848305D01*
X1816417Y849471D01*
X1817945Y850054D01*
X1819473Y849471D01*
X1820565Y848305D01*
X1821220Y846846D01*
Y838388D01*
G01Y846846D02*
X1821875Y848305D01*
X1822966Y849471D01*
X1824495Y850054D01*
X1826023Y849471D01*
X1827115Y848305D01*
X1827770Y846555D01*
Y838388D01*
G01X1838720Y850054D02*
Y838388D01*
G01Y854721D02*
X1838283Y855013D01*
Y855596D01*
X1838720Y855888D01*
X1839157Y855596D01*
Y855013D01*
X1838720Y854721D01*
G01X1856220Y838388D02*
Y855888D01*
G01X1870445Y840429D02*
X1871537Y839263D01*
X1873065Y838388D01*
X1874375D01*
X1875685Y838971D01*
X1876558Y839846D01*
X1876995Y841012D01*
X1876777Y842763D01*
X1875903Y843638D01*
X1871973Y845388D01*
X1871100Y847430D01*
X1871537Y848888D01*
X1872410Y849763D01*
X1873720Y850054D01*
X1875030Y849763D01*
X1876340Y848888D01*
G01X1892312Y832555D02*
X1894495Y835471D01*
X1895587Y838388D01*
Y850054D01*
X1894495Y852971D01*
X1892312Y855888D01*
G01X1753840Y769088D02*
Y786588D01*
X1745761Y774046D01*
X1756679D01*
G01X1768720Y768505D02*
X1768283Y768796D01*
Y769380D01*
X1768720Y769671D01*
X1769157Y769380D01*
Y768796D01*
X1768720Y768505D01*
G01X1786220Y786588D02*
X1784473Y786005D01*
X1783163Y784546D01*
X1782290Y782797D01*
X1781635Y780463D01*
X1781417Y777838D01*
X1781635Y775213D01*
X1782290Y772879D01*
X1783163Y771129D01*
X1784473Y769671D01*
X1786220Y769088D01*
X1787966Y769671D01*
X1789277Y771129D01*
X1790150Y772879D01*
X1790805Y775213D01*
X1791023Y777838D01*
X1790805Y780463D01*
X1790150Y782797D01*
X1789277Y784546D01*
X1787966Y786005D01*
X1786220Y786588D01*
G01X1799790Y768505D02*
X1807650Y786588D01*
G01X1821220Y769088D02*
X1822748Y769380D01*
X1824495Y770254D01*
X1825587Y771712D01*
X1826023Y773755D01*
X1825587Y775796D01*
X1824277Y777546D01*
X1822312Y778421D01*
X1820128D01*
X1818818Y779005D01*
X1817726Y780463D01*
X1817290Y782504D01*
X1817945Y784546D01*
X1819473Y786005D01*
X1821220Y786588D01*
X1822966Y786005D01*
X1824495Y784546D01*
X1825150Y782504D01*
X1824713Y780463D01*
X1823622Y779005D01*
X1822312Y778421D01*
X1820128D01*
X1818163Y777546D01*
X1816853Y775796D01*
X1816417Y773755D01*
X1816853Y771712D01*
X1817945Y770254D01*
X1819692Y769380D01*
X1821220Y769088D01*
G01X1838720Y768505D02*
X1838283Y768796D01*
Y769380D01*
X1838720Y769671D01*
X1839157Y769380D01*
Y768796D01*
X1838720Y768505D01*
G01X1856220Y786588D02*
X1854473Y786005D01*
X1853163Y784546D01*
X1852290Y782797D01*
X1851635Y780463D01*
X1851417Y777838D01*
X1851635Y775213D01*
X1852290Y772879D01*
X1853163Y771129D01*
X1854473Y769671D01*
X1856220Y769088D01*
X1857966Y769671D01*
X1859277Y771129D01*
X1860150Y772879D01*
X1860805Y775213D01*
X1861023Y777838D01*
X1860805Y780463D01*
X1860150Y782797D01*
X1859277Y784546D01*
X1857966Y786005D01*
X1856220Y786588D01*
G01X1746417Y806362D02*
X1747726Y804904D01*
X1749255Y804030D01*
X1751220Y803738D01*
X1753185Y804321D01*
X1754713Y805488D01*
X1755805Y807529D01*
X1756023Y809863D01*
X1755587Y812196D01*
X1754495Y813655D01*
X1752966Y814821D01*
X1751438Y815113D01*
X1749910Y814821D01*
X1747945Y813655D01*
X1748600Y821238D01*
X1754495D01*
G01X1768720Y803155D02*
X1768283Y803446D01*
Y804030D01*
X1768720Y804321D01*
X1769157Y804030D01*
Y803446D01*
X1768720Y803155D01*
G01X1781417Y806362D02*
X1782726Y804904D01*
X1784255Y804030D01*
X1786220Y803738D01*
X1788185Y804321D01*
X1789713Y805488D01*
X1790805Y807529D01*
X1791023Y809863D01*
X1790587Y812196D01*
X1789495Y813655D01*
X1787966Y814821D01*
X1786438Y815113D01*
X1784910Y814821D01*
X1782945Y813655D01*
X1783600Y821238D01*
X1789495D01*
G01X1799790Y803155D02*
X1807650Y821238D01*
G01X1820783Y803738D02*
X1821220Y807529D01*
X1821875Y810738D01*
X1822748Y813655D01*
X1823840Y816863D01*
X1825587Y821238D01*
X1816853D01*
G01X1838720Y803155D02*
X1838283Y803446D01*
Y804030D01*
X1838720Y804321D01*
X1839157Y804030D01*
Y803446D01*
X1838720Y803155D01*
G01X1851417Y806362D02*
X1852726Y804904D01*
X1854255Y804030D01*
X1856220Y803738D01*
X1858185Y804321D01*
X1859713Y805488D01*
X1860805Y807529D01*
X1861023Y809863D01*
X1860587Y812196D01*
X1859495Y813655D01*
X1857966Y814821D01*
X1856438Y815113D01*
X1854910Y814821D01*
X1852945Y813655D01*
X1853600Y821238D01*
X1859495D01*
G01X1978720Y855888D02*
Y838388D01*
G01X1973698Y855888D02*
X1983742D01*
G01X1996220Y838388D02*
Y846263D01*
X1991853Y855888D01*
G01X2000587D02*
X1996220Y846263D01*
G01X2009353Y838388D02*
Y855888D01*
X2014593D01*
X2016340Y855013D01*
X2017650Y852971D01*
X2018087Y850638D01*
X2017650Y848305D01*
X2016558Y846555D01*
X2014593Y845679D01*
X2009353D01*
G01X2035587Y838388D02*
X2026853D01*
Y855888D01*
X2035587D01*
G01X2032093Y847430D02*
X2026853D01*
G01X1991417Y769088D02*
Y786588D01*
X1995783D01*
X1997530Y785713D01*
X1998840Y784546D01*
X1999932Y782797D01*
X2000805Y780754D01*
X2001023Y777838D01*
X2000805Y774921D01*
X1999932Y772879D01*
X1998840Y771129D01*
X1997530Y769963D01*
X1995783Y769088D01*
X1991417D01*
G01X2009353D02*
Y786588D01*
X2014593D01*
X2016340Y785713D01*
X2017650Y783671D01*
X2018087Y781338D01*
X2017650Y779005D01*
X2016558Y777255D01*
X2014593Y776379D01*
X2009353D01*
G01X1991417Y803738D02*
Y821238D01*
X1995783D01*
X1997530Y820363D01*
X1998840Y819196D01*
X1999932Y817447D01*
X2000805Y815404D01*
X2001023Y812488D01*
X2000805Y809571D01*
X1999932Y807529D01*
X1998840Y805779D01*
X1997530Y804613D01*
X1995783Y803738D01*
X1991417D01*
G01X2009353D02*
Y821238D01*
X2014593D01*
X2016340Y820363D01*
X2017650Y818321D01*
X2018087Y815988D01*
X2017650Y813655D01*
X2016558Y811905D01*
X2014593Y811029D01*
X2009353D01*
G01X2079353Y838388D02*
Y855888D01*
X2084812D01*
X2086558Y855013D01*
X2087650Y853846D01*
X2088087Y851513D01*
X2087650Y849179D01*
X2086340Y847721D01*
X2084812Y846846D01*
X2079353D01*
G01X2084812D02*
X2088087Y838388D01*
G01X2097945Y846263D02*
X2104932D01*
X2104277Y848305D01*
X2103185Y849471D01*
X2101657Y850054D01*
X2100128Y849763D01*
X2098818Y848888D01*
X2097945Y846846D01*
X2097508Y845096D01*
Y843346D01*
X2097945Y841596D01*
X2099037Y839846D01*
X2100347Y838680D01*
X2101875Y838388D01*
X2103403Y838971D01*
X2104932Y840721D01*
G01X2117410Y838388D02*
Y853263D01*
X2117847Y854721D01*
X2118720Y855596D01*
X2120030Y855888D01*
X2121340Y855305D01*
X2121995Y853846D01*
G01X2119375Y848888D02*
X2115008D01*
G01X2136220Y837805D02*
X2135783Y838096D01*
Y838680D01*
X2136220Y838971D01*
X2136657Y838680D01*
Y838096D01*
X2136220Y837805D01*
G01X2166853Y838388D02*
Y855888D01*
X2172093D01*
X2173840Y855013D01*
X2175150Y852971D01*
X2175587Y850638D01*
X2175150Y848305D01*
X2174058Y846555D01*
X2172093Y845679D01*
X2166853D01*
G01X2188720Y838388D02*
Y855888D01*
G01X2210150Y838388D02*
Y850054D01*
G01Y848013D02*
X2209277Y849179D01*
X2207966Y849763D01*
X2206438Y850054D01*
X2204910Y849471D01*
X2203600Y848305D01*
X2202726Y846555D01*
X2202290Y844221D01*
X2202726Y841888D01*
X2203600Y840138D01*
X2204910Y838971D01*
X2206438Y838388D01*
X2207966Y838680D01*
X2209277Y839554D01*
X2210150Y840721D01*
G01X2220008Y838388D02*
Y850054D01*
G01Y847138D02*
X2220882Y848596D01*
X2222192Y849763D01*
X2223938Y850054D01*
X2225466Y849763D01*
X2226777Y848596D01*
X2227432Y846555D01*
Y838388D01*
G01X2237945Y846263D02*
X2244932D01*
X2244277Y848305D01*
X2243185Y849471D01*
X2241657Y850054D01*
X2240128Y849763D01*
X2238818Y848888D01*
X2237945Y846846D01*
X2237508Y845096D01*
Y843346D01*
X2237945Y841596D01*
X2239037Y839846D01*
X2240347Y838680D01*
X2241875Y838388D01*
X2243403Y838971D01*
X2244932Y840721D01*
G01X2123103Y786588D02*
Y769088D01*
X2131837D01*
G01X2140822Y783671D02*
X2142132Y785421D01*
X2143660Y786296D01*
X2145407Y786588D01*
X2147590Y786005D01*
X2149118Y784546D01*
X2149555Y782797D01*
X2149337Y781046D01*
X2148463Y779588D01*
X2144097Y776671D01*
X2142132Y774630D01*
X2140822Y771712D01*
X2140385Y769088D01*
X2149555D01*
G01X2158540Y768505D02*
X2166400Y786588D01*
G01X2175603D02*
Y769088D01*
X2184337D01*
G01X2200090D02*
Y786588D01*
X2192011Y774046D01*
X2202929D01*
G01X2123103Y821238D02*
Y803738D01*
X2131837D01*
G01X2140822Y818321D02*
X2142132Y820071D01*
X2143660Y820946D01*
X2145407Y821238D01*
X2147590Y820655D01*
X2149118Y819196D01*
X2149555Y817447D01*
X2149337Y815696D01*
X2148463Y814238D01*
X2144097Y811321D01*
X2142132Y809280D01*
X2140822Y806362D01*
X2140385Y803738D01*
X2149555D01*
G01X2158540Y803155D02*
X2166400Y821238D01*
G01X2175603D02*
Y803738D01*
X2184337D01*
G01X2200090D02*
Y821238D01*
X2192011Y808696D01*
X2202929D01*
G01X2359020Y815404D02*
Y803738D01*
G01Y820071D02*
X2358583Y820363D01*
Y820946D01*
X2359020Y821238D01*
X2359457Y820946D01*
Y820363D01*
X2359020Y820071D01*
G01X2373245Y805779D02*
X2374337Y804613D01*
X2375865Y803738D01*
X2377175D01*
X2378485Y804321D01*
X2379358Y805196D01*
X2379795Y806362D01*
X2379577Y808113D01*
X2378703Y808988D01*
X2374773Y810738D01*
X2373900Y812780D01*
X2374337Y814238D01*
X2375210Y815113D01*
X2376520Y815404D01*
X2377830Y815113D01*
X2379140Y814238D01*
G01X2406498Y803738D02*
Y821238D01*
X2416542Y803738D01*
Y821238D01*
G01X2429020Y803738D02*
X2427273Y804030D01*
X2425745Y805196D01*
X2424435Y806946D01*
X2423561Y808988D01*
X2423125Y811321D01*
Y813655D01*
X2423561Y815988D01*
X2424435Y818030D01*
X2425745Y819779D01*
X2427273Y820946D01*
X2429020Y821238D01*
X2430766Y820946D01*
X2432295Y819779D01*
X2433605Y818030D01*
X2434479Y815988D01*
X2434915Y813655D01*
Y811321D01*
X2434479Y808988D01*
X2433605Y806946D01*
X2432295Y805196D01*
X2430766Y804030D01*
X2429020Y803738D01*
G01X2446520Y821238D02*
Y803738D01*
G01X2441498Y821238D02*
X2451542D01*
G01X2477808Y815404D02*
Y807238D01*
X2478682Y805196D01*
X2479992Y804030D01*
X2481520Y803738D01*
X2483048Y804030D01*
X2484358Y805196D01*
X2485232Y807238D01*
G01Y803738D02*
Y815404D01*
G01X2495745Y805779D02*
X2496837Y804613D01*
X2498365Y803738D01*
X2499675D01*
X2500985Y804321D01*
X2501858Y805196D01*
X2502295Y806362D01*
X2502077Y808113D01*
X2501203Y808988D01*
X2497273Y810738D01*
X2496400Y812780D01*
X2496837Y814238D01*
X2497710Y815113D01*
X2499020Y815404D01*
X2500330Y815113D01*
X2501640Y814238D01*
G01X2513245Y811613D02*
X2520232D01*
X2519577Y813655D01*
X2518485Y814821D01*
X2516957Y815404D01*
X2515428Y815113D01*
X2514118Y814238D01*
X2513245Y812196D01*
X2512808Y810446D01*
Y808696D01*
X2513245Y806946D01*
X2514337Y805196D01*
X2515647Y804030D01*
X2517175Y803738D01*
X2518703Y804321D01*
X2520232Y806071D01*
G01X2537950Y821238D02*
Y803738D01*
G01Y806362D02*
X2537077Y804904D01*
X2535766Y804030D01*
X2534238Y803738D01*
X2532492Y804321D01*
X2531182Y805779D01*
X2530308Y807529D01*
X2530090Y809571D01*
X2530308Y811613D01*
X2531182Y813363D01*
X2532492Y814821D01*
X2534238Y815404D01*
X2535766Y815113D01*
X2536858Y814529D01*
X2537950Y813363D01*
G01X2284217Y837805D02*
X2293823Y850638D01*
G01X2289020Y852971D02*
Y835471D01*
G01X2293823Y837805D02*
X2284217Y850638D01*
G01X2282470Y844221D02*
X2295570D01*
G01X2321182D02*
X2326858D01*
G01X2354217Y838388D02*
Y855888D01*
X2358583D01*
X2360330Y855013D01*
X2361640Y853846D01*
X2362732Y852097D01*
X2363605Y850054D01*
X2363823Y847138D01*
X2363605Y844221D01*
X2362732Y842179D01*
X2361640Y840429D01*
X2360330Y839263D01*
X2358583Y838388D01*
X2354217D01*
G01X2373245Y846263D02*
X2380232D01*
X2379577Y848305D01*
X2378485Y849471D01*
X2376957Y850054D01*
X2375428Y849763D01*
X2374118Y848888D01*
X2373245Y846846D01*
X2372808Y845096D01*
Y843346D01*
X2373245Y841596D01*
X2374337Y839846D01*
X2375647Y838680D01*
X2377175Y838388D01*
X2378703Y838971D01*
X2380232Y840721D01*
G01X2390308Y838388D02*
Y850054D01*
G01Y847138D02*
X2391182Y848596D01*
X2392492Y849763D01*
X2394238Y850054D01*
X2395766Y849763D01*
X2397077Y848596D01*
X2397732Y846555D01*
Y838388D01*
G01X2411520D02*
X2410210Y838680D01*
X2408900Y839846D01*
X2408026Y841888D01*
X2407590Y844221D01*
X2408026Y846555D01*
X2408900Y848596D01*
X2410210Y849763D01*
X2411520Y850054D01*
X2412830Y849763D01*
X2414140Y848596D01*
X2415013Y846555D01*
X2415232Y844221D01*
X2415013Y841888D01*
X2414140Y839846D01*
X2412830Y838680D01*
X2411520Y838388D01*
G01X2429020Y855888D02*
Y838388D01*
G01X2425963Y850054D02*
X2432077D01*
G01X2443245Y846263D02*
X2450232D01*
X2449577Y848305D01*
X2448485Y849471D01*
X2446957Y850054D01*
X2445428Y849763D01*
X2444118Y848888D01*
X2443245Y846846D01*
X2442808Y845096D01*
Y843346D01*
X2443245Y841596D01*
X2444337Y839846D01*
X2445647Y838680D01*
X2447175Y838388D01*
X2448703Y838971D01*
X2450232Y840721D01*
G01X2460745Y840429D02*
X2461837Y839263D01*
X2463365Y838388D01*
X2464675D01*
X2465985Y838971D01*
X2466858Y839846D01*
X2467295Y841012D01*
X2467077Y842763D01*
X2466203Y843638D01*
X2462273Y845388D01*
X2461400Y847430D01*
X2461837Y848888D01*
X2462710Y849763D01*
X2464020Y850054D01*
X2465330Y849763D01*
X2466640Y848888D01*
G01X2499020Y855888D02*
Y838388D01*
G01X2495963Y850054D02*
X2502077D01*
G01X2512808Y838388D02*
Y855888D01*
G01Y847430D02*
X2513900Y848888D01*
X2514992Y849763D01*
X2516738Y850054D01*
X2518048Y849763D01*
X2519577Y848596D01*
X2520232Y846846D01*
Y838388D01*
G01X2537950D02*
Y850054D01*
G01Y848013D02*
X2537077Y849179D01*
X2535766Y849763D01*
X2534238Y850054D01*
X2532710Y849471D01*
X2531400Y848305D01*
X2530526Y846555D01*
X2530090Y844221D01*
X2530526Y841888D01*
X2531400Y840138D01*
X2532710Y838971D01*
X2534238Y838388D01*
X2535766Y838680D01*
X2537077Y839554D01*
X2537950Y840721D01*
G01X2551520Y855888D02*
Y838388D01*
G01X2548463Y850054D02*
X2554577D01*
G01X2586520Y855888D02*
Y838388D01*
G01X2583463Y850054D02*
X2589577D01*
G01X2600308Y838388D02*
Y855888D01*
G01Y847430D02*
X2601400Y848888D01*
X2602492Y849763D01*
X2604238Y850054D01*
X2605548Y849763D01*
X2607077Y848596D01*
X2607732Y846846D01*
Y838388D01*
G01X2621520Y850054D02*
Y838388D01*
G01Y854721D02*
X2621083Y855013D01*
Y855596D01*
X2621520Y855888D01*
X2621957Y855596D01*
Y855013D01*
X2621520Y854721D01*
G01X2635745Y840429D02*
X2636837Y839263D01*
X2638365Y838388D01*
X2639675D01*
X2640985Y838971D01*
X2641858Y839846D01*
X2642295Y841012D01*
X2642077Y842763D01*
X2641203Y843638D01*
X2637273Y845388D01*
X2636400Y847430D01*
X2636837Y848888D01*
X2637710Y849763D01*
X2639020Y850054D01*
X2640330Y849763D01*
X2641640Y848888D01*
G01X2671400Y855888D02*
X2676640D01*
G01X2674020D02*
Y838388D01*
G01X2671400D02*
X2676640D01*
G01X2684970D02*
Y850054D01*
G01Y846846D02*
X2685625Y848305D01*
X2686717Y849471D01*
X2688245Y850054D01*
X2689773Y849471D01*
X2690865Y848305D01*
X2691520Y846846D01*
Y838388D01*
G01Y846846D02*
X2692175Y848305D01*
X2693266Y849471D01*
X2694795Y850054D01*
X2696323Y849471D01*
X2697415Y848305D01*
X2698070Y846555D01*
Y838388D01*
G01X2705090Y832555D02*
Y850054D01*
G01Y847430D02*
X2706182Y848888D01*
X2707273Y849763D01*
X2709020Y850054D01*
X2710548Y849763D01*
X2712077Y848305D01*
X2712732Y846263D01*
X2712950Y844221D01*
X2712732Y842179D01*
X2712077Y840138D01*
X2710766Y838971D01*
X2709020Y838388D01*
X2707492Y838680D01*
X2705963Y839554D01*
X2705090Y840721D01*
G01X2723245Y846263D02*
X2730232D01*
X2729577Y848305D01*
X2728485Y849471D01*
X2726957Y850054D01*
X2725428Y849763D01*
X2724118Y848888D01*
X2723245Y846846D01*
X2722808Y845096D01*
Y843346D01*
X2723245Y841596D01*
X2724337Y839846D01*
X2725647Y838680D01*
X2727175Y838388D01*
X2728703Y838971D01*
X2730232Y840721D01*
G01X2747950Y855888D02*
Y838388D01*
G01Y841012D02*
X2747077Y839554D01*
X2745766Y838680D01*
X2744238Y838388D01*
X2742492Y838971D01*
X2741182Y840429D01*
X2740308Y842179D01*
X2740090Y844221D01*
X2740308Y846263D01*
X2741182Y848013D01*
X2742492Y849471D01*
X2744238Y850054D01*
X2745766Y849763D01*
X2746858Y849179D01*
X2747950Y848013D01*
G01X2765450Y838388D02*
Y850054D01*
G01Y848013D02*
X2764577Y849179D01*
X2763266Y849763D01*
X2761738Y850054D01*
X2760210Y849471D01*
X2758900Y848305D01*
X2758026Y846555D01*
X2757590Y844221D01*
X2758026Y841888D01*
X2758900Y840138D01*
X2760210Y838971D01*
X2761738Y838388D01*
X2763266Y838680D01*
X2764577Y839554D01*
X2765450Y840721D01*
G01X2775308Y838388D02*
Y850054D01*
G01Y847138D02*
X2776182Y848596D01*
X2777492Y849763D01*
X2779238Y850054D01*
X2780766Y849763D01*
X2782077Y848596D01*
X2782732Y846555D01*
Y838388D01*
G01X2800013Y848596D02*
X2798485Y849763D01*
X2797175Y850054D01*
X2795428Y849471D01*
X2794118Y848305D01*
X2793245Y846263D01*
X2793026Y844221D01*
X2793245Y842179D01*
X2794118Y840429D01*
X2795428Y838971D01*
X2797175Y838388D01*
X2798703Y838971D01*
X2800013Y840138D01*
G01X2810745Y846263D02*
X2817732D01*
X2817077Y848305D01*
X2815985Y849471D01*
X2814457Y850054D01*
X2812928Y849763D01*
X2811618Y848888D01*
X2810745Y846846D01*
X2810308Y845096D01*
Y843346D01*
X2810745Y841596D01*
X2811837Y839846D01*
X2813147Y838680D01*
X2814675Y838388D01*
X2816203Y838971D01*
X2817732Y840721D01*
G01X1425733Y-51181D02*
X-29385D01*
G01X-33322Y-47244D02*
G03X-29385Y-51181I3937J0D01*
G01X-33322Y-47244D02*
Y893701D01*
G01X-7874Y102402D02*
Y212205D01*
G01Y102402D02*
G03X0Y94528I7874J0D01*
G01Y212205D02*
G03X-7874I-3937J0D01*
G01Y237402D02*
G03X0I3937J-1D01*
G01X-7874D02*
Y406693D01*
G01X0D02*
G03X-7874I-3937J0D01*
G01Y431890D02*
G03X0I3937J0D01*
G01X-7874D02*
Y601181D01*
G01X0D02*
G03X-7874I-3937J0D01*
G01Y626378D02*
Y795669D01*
G01Y626378D02*
G03X0I3937J0D01*
G01Y795669D02*
G03X-7874I-3937J0D01*
G01Y820866D02*
G03X0I3937J0D01*
G01X-7874Y844488D02*
Y820866D01*
G01X-3937Y848425D02*
G03X-7874Y844488I0J-3937D01*
G01X93307Y848425D02*
X-3937D01*
G01X-29385Y897638D02*
G03X-33322Y893701I0J-3937D01*
G01X-29385Y897638D02*
X93307D01*
G01X98425Y94528D02*
X0D01*
G01X1400000Y36220D02*
G03X1398031Y38189I-1969J0D01*
G01X1396654D01*
G02X1394685Y40157I0J1969D01*
G01Y71654D01*
G02X1396654Y73622I1969J-1D01*
G01X1398031D01*
G03X1400000Y75591I0J1969D01*
G01Y836614D01*
G03X1396063Y840551I-3937J0D01*
G01X1368504D01*
G02X1363386Y845669I0J5118D01*
G01Y871654D01*
G03X1361417Y873622I-1969J-1D01*
G01X1358268D01*
G02X1356299Y875591I0J1969D01*
G01Y892521D01*
X1352363Y897638D01*
X1218110D01*
X1214173Y892520D01*
Y875984D01*
G02X1205512I-4331J0D01*
G01Y892520D01*
X1201575Y897638D01*
X1029528D01*
X1025591Y892520D01*
Y875591D01*
G02X1023622Y873622I-1969J0D01*
G01X1020472D01*
G03X1018504Y871654I0J-1968D01*
G01Y845669D01*
G02X1013386Y840551I-5118J0D01*
G01X1008433D01*
G03X988748Y820866I0J-19685D01*
G01Y650669D01*
G02X983748Y645669I-5000J0D01*
G01X926819D01*
G02X921819Y650669I0J5000D01*
G01Y820866D01*
G03X902134Y840551I-19685J0D01*
G01X872441D01*
G02X867323Y845669I0J5118D01*
G01Y871654D01*
G03X865354Y873622I-1969J-1D01*
G01X862205D01*
G02X860236Y875591I0J1969D01*
G01Y892521D01*
X856300Y897638D01*
X722048D01*
X718110Y892519D01*
Y875984D01*
G02X709449I-4331J0D01*
G01Y892520D01*
X705512Y897638D01*
X533465D01*
X529528Y892520D01*
Y875591D01*
G02X527559Y873622I-1969J0D01*
G01X524409D01*
G03X522441Y871654I0J-1968D01*
G01Y845669D01*
G02X517323Y840551I-5118J0D01*
G01X455118D01*
G02X450000Y845669I0J5118D01*
G01Y871654D01*
G03X448031Y873622I-1968J0D01*
G01X444882D01*
G02X442913Y875591I0J1969D01*
G01Y892521D01*
X438977Y897638D01*
X304725D01*
X300787Y892519D01*
Y875984D01*
G02X292126I-4331J0D01*
G01Y892521D01*
X288190Y897638D01*
X116142D01*
X112205Y892520D01*
Y875591D01*
G02X110236Y873622I-1969J0D01*
G01X107087D01*
G03X105118Y871654I0J-1969D01*
G01Y845669D01*
G02X100000Y840551I-5118J0D01*
G01X3937D01*
G03X0Y836614I0J-3937D01*
G01Y110276D01*
G03X7874Y102402I7874J0D01*
G01X196654D01*
G02X204528Y94528I0J-7874D01*
G01Y7874D01*
G03X212402Y0I7874J0D01*
G01X471014D01*
G02X478888Y-7874I0J-7874D01*
G01Y-11811D01*
G03X486762Y-19685I7874J0D01*
G01X1302165D01*
G03X1306102Y-15748I0J3937D01*
G01Y-3937D01*
G02X1310039Y0I3937J0D01*
G01X1396063D01*
G03X1400000Y3937I0J3937D01*
G01Y36220D01*
G01X93307Y848425D02*
G03X97244Y852362I0J3937D01*
G01Y893701D02*
Y852362D01*
G01Y893701D02*
G03X93307Y897638I-3937J0D01*
G01X192717Y94528D02*
X123622D01*
G01Y102402D02*
G03Y94528I0J-3937D01*
G01X98425D02*
G03Y102402I0J3937D01*
G01X196654Y0D02*
G03X204528Y-7874I7874J0D01*
G01X196654Y0D02*
Y29961D01*
G01X204528D02*
G03X196654I-3937J0D01*
G01Y55157D02*
Y90591D01*
G01Y55157D02*
G03X204528I3937J0D01*
G01X196654Y90591D02*
G03X192717Y94528I-3937J0D01*
G01X232077Y-7874D02*
G03Y0I0J3937D01*
G01Y-7874D02*
X204528D01*
G01X434439D02*
X257274D01*
G01Y0D02*
G03Y-7874I0J-3937D01*
G01X365945Y38188D02*
G03X367914Y40156I0J1969D01*
G01X354134D02*
G03X356103Y38188I1969J1D01*
G01D02*
X365945D01*
G01X354134Y71653D02*
Y40156D01*
G01X367914Y71653D02*
G03X365945Y73621I-1969J-1D01*
G01X356103D02*
G03X354134Y71653I0J-1969D01*
G01X365945Y73621D02*
X356103D01*
G01X367914Y40156D02*
Y71653D01*
G01X434439Y-7874D02*
G03Y0I0J3937D01*
G01X471014Y-15748D02*
G03X463140Y-7874I-7874J0D01*
G01D02*
X459636D01*
G01Y0D02*
G03Y-7874I0J-3937D01*
G01X707234Y-27559D02*
X478888D01*
G01X471014Y-19685D02*
G03X478888Y-27559I7874J0D01*
G01X471014Y-19685D02*
Y-15748D01*
G01X870226Y-27559D02*
X732431D01*
G01Y-19685D02*
G03Y-27559I0J-3937D01*
G01X707234D02*
G03Y-19685I0J3937D01*
G01X870226Y-27559D02*
G03Y-19685I1J3937D01*
G01X1072589Y-27559D02*
X895423D01*
G01Y-19685D02*
G03Y-27559I0J-3937D01*
G01X1072589D02*
G03Y-19685I0J3937D01*
G01X1097785D02*
G03Y-27559I1J-3937D01*
G01X1336086Y-8662D02*
X1318701D01*
G03X1314764Y-12599I0J-3937D01*
G01Y-23622D01*
G02X1310827Y-27559I-3937J0D01*
G01X1097785D01*
G01X1336086Y-8662D02*
G03Y-1I0J4330D01*
G01X1361283D02*
G03Y-8662I0J-4330D01*
G01X1407874Y13026D02*
Y-4725D01*
G02X1403937Y-8662I-3937J0D01*
G01X1361283D01*
G01X1403937Y848425D02*
X1375197D01*
G01X1371260Y852362D02*
G03X1375197Y848425I3937J0D01*
G01X1371260Y852362D02*
Y893701D01*
G01X1375197Y897638D02*
G03X1371260Y893701I0J-3937D01*
G01X1375197Y897638D02*
X1425733D01*
G01X1407874Y30709D02*
Y219685D01*
G01X1400000Y30709D02*
G03X1407874I3937J0D01*
G01Y13026D02*
G03X1400000I-3937J-1D01*
G01X1407874Y219685D02*
G03X1400000I-3937J0D01*
G01Y244882D02*
G03X1407874I3937J0D01*
G01Y414173D02*
Y244882D01*
G01Y608661D02*
Y439370D01*
G01X1400000D02*
G03X1407874I3937J0D01*
G01Y414173D02*
G03X1400000I-3937J0D01*
G01X1407874Y608661D02*
G03X1400000I-3937J0D01*
G01Y626378D02*
G03X1407874I3937J0D01*
G01Y795669D02*
Y626378D01*
G01Y795669D02*
G03X1400000I-3937J0D01*
G01Y820866D02*
G03X1407874I3937J0D01*
G01Y844488D02*
Y820866D01*
G01Y844488D02*
G03X1403937Y848425I-3937J0D01*
G01X1429670Y893701D02*
Y-47244D01*
G01X1425733Y-51181D02*
G03X1429670Y-47244I0J3937D01*
G01Y893701D02*
G03X1425733Y897638I-3937J0D01*
G54D13*
G01X29449Y410023D02*
Y426080D01*
G01X28149Y409484D02*
Y425541D01*
G01X54894Y384578D02*
X29449Y410023D01*
G01X53594Y384039D02*
X28149Y409484D01*
G01D02*
Y425541D01*
G01X29449Y410023D02*
Y426080D01*
G01X53594Y384039D02*
X28149Y409484D01*
G01X54894Y384578D02*
X29449Y410023D01*
G01D02*
Y426080D01*
G01X28149Y409484D02*
Y425541D01*
G01X54894Y384578D02*
X29449Y410023D01*
G01X53594Y384039D02*
X28149Y409484D01*
G01D02*
Y425541D01*
G01X29449Y410023D02*
Y426080D01*
G01X53594Y384039D02*
X28149Y409484D01*
G01X54894Y384578D02*
X29449Y410023D01*
G01X16665Y438864D02*
Y521209D01*
G01X15365Y438325D02*
Y521748D01*
G01X29449Y426080D02*
X16665Y438864D01*
G01X28149Y425541D02*
X15365Y438325D01*
G01D02*
Y521748D01*
G01X16665Y438864D02*
Y521209D01*
G01X28149Y425541D02*
X15365Y438325D01*
G01X29449Y426080D02*
X16665Y438864D01*
G01D02*
Y521209D01*
G01X15365Y438325D02*
Y521748D01*
G01X29449Y426080D02*
X16665Y438864D01*
G01X28149Y425541D02*
X15365Y438325D01*
G01D02*
Y521748D01*
G01X16665Y438864D02*
Y521209D01*
G01X28149Y425541D02*
X15365Y438325D01*
G01X29449Y426080D02*
X16665Y438864D01*
G01Y521209D02*
X47478Y552022D01*
G01X15365Y521748D02*
X46939Y553322D01*
G01X15365Y521748D02*
X46939Y553322D01*
G01X16665Y521209D02*
X47478Y552022D01*
G01X16665Y521209D02*
X47478Y552022D01*
G01X15365Y521748D02*
X46939Y553322D01*
G01X15365Y521748D02*
X46939Y553322D01*
G01X16665Y521209D02*
X47478Y552022D01*
G01X63950Y339511D02*
X65196Y338265D01*
G01X63950Y339511D02*
X65196Y338265D01*
G01X73338Y364801D02*
X54894Y383245D01*
G01X72799Y363501D02*
X53594Y382706D01*
G01X72799Y363501D02*
X53594Y382706D01*
G01X73338Y364801D02*
X54894Y383245D01*
G01X73338Y364801D02*
X54894Y383245D01*
G01X72799Y363501D02*
X53594Y382706D01*
G01X72799Y363501D02*
X53594Y382706D01*
G01X73338Y364801D02*
X54894Y383245D01*
G01D02*
Y384578D01*
G01X53594Y382706D02*
Y384039D01*
G01Y382706D02*
Y384039D01*
G01X54894Y383245D02*
Y384578D01*
G01Y383245D02*
Y384578D01*
G01X53594Y382706D02*
Y384039D01*
G01Y382706D02*
Y384039D01*
G01X54894Y383245D02*
Y384578D01*
G01X48109Y553325D02*
X71209Y576425D01*
G01X48648Y552025D02*
X71748Y575125D01*
G01X48109Y553325D02*
X71209Y576425D01*
G01X47711Y552025D02*
X48648D01*
G01X47172Y553325D02*
X48109D01*
G01X47478Y552022D02*
X47708D01*
G01X47172Y553325D02*
X48109D01*
G01D02*
X71209Y576425D01*
G01X48648Y552025D02*
X71748Y575125D01*
G01X47172Y553325D02*
X48109D01*
G01X47711Y552025D02*
X48648D01*
G01X47478Y552022D02*
X47708D01*
G01X48109Y553325D02*
X71209Y576425D01*
G01X48648Y552025D02*
X71748Y575125D01*
G01X48109Y553325D02*
X71209Y576425D01*
G01X47711Y552025D02*
X48648D01*
G01X47172Y553325D02*
X48109D01*
G01X47478Y552022D02*
X47708D01*
G01X47172Y553325D02*
X48109D01*
G01D02*
X71209Y576425D01*
G01X48648Y552025D02*
X71748Y575125D01*
G01X47172Y553325D02*
X48109D01*
G01X47711Y552025D02*
X48648D01*
G01X47478Y552022D02*
X47708D01*
G01X93918Y326063D02*
X103948Y319551D01*
G01X92978Y325123D02*
X103442Y318329D01*
G01X88145Y334951D02*
X93918Y326063D01*
G01X87205Y334011D02*
X92978Y325123D01*
G01X85956Y336373D02*
X88145Y334951D01*
G01X85449Y335151D02*
X87205Y334011D01*
G01X84084Y336772D02*
X85956Y336373D01*
G01X84084Y335442D02*
X85449Y335151D01*
G01X75508Y334948D02*
X84084Y336772D01*
G01X75508Y333618D02*
X84084Y335442D01*
G01X71322Y335838D02*
X75508Y334948D01*
G01X71052Y334566D02*
X75508Y333618D01*
G01X70816Y334616D02*
X71052Y334565D01*
G01X66019Y339281D02*
X71322Y335838D01*
G01X65196Y338265D02*
X70816Y334616D01*
G01X65250Y340050D02*
X66019Y339281D01*
G01X65250Y341150D02*
Y340050D01*
G01X63950Y341150D02*
Y339511D01*
G01X92978Y325123D02*
X103442Y318329D01*
G01X93918Y326063D02*
X103948Y319551D01*
G01X87205Y334011D02*
X92978Y325123D01*
G01X88145Y334951D02*
X93918Y326063D01*
G01X85449Y335151D02*
X87205Y334011D01*
G01X85956Y336373D02*
X88145Y334951D01*
G01X84084Y335442D02*
X85449Y335151D01*
G01X84084Y336772D02*
X85956Y336373D01*
G01X75508Y333618D02*
X84084Y335442D01*
G01X75508Y334948D02*
X84084Y336772D01*
G01X71052Y334566D02*
X75508Y333618D01*
G01X71322Y335838D02*
X75508Y334948D01*
G01X70816Y334616D02*
X71052Y334565D01*
G01X71322Y335838D02*
X75508Y334948D01*
G01X65196Y338265D02*
X70816Y334616D01*
G01X66019Y339281D02*
X71322Y335838D01*
G01X65250Y340050D02*
X66019Y339281D01*
G01X63950Y341150D02*
Y339511D01*
G01X65250Y341150D02*
Y340050D01*
G01X76287Y364801D02*
X73338D01*
G01X75748Y363501D02*
X72799D01*
G01X80739Y360349D02*
X76287Y364801D01*
G01X80200Y359049D02*
X75748Y363501D01*
G01X85461Y360349D02*
X80739D01*
G01X84922Y359049D02*
X80200D01*
G01X89684Y356126D02*
X85461Y360349D01*
G01X89145Y354826D02*
X84922Y359049D01*
G01X92897Y356126D02*
X89684D01*
G01X92358Y354826D02*
X89145D01*
G01X106248Y342775D02*
X92897Y356126D01*
G01X105709Y341475D02*
X92358Y354826D01*
G01X75748Y363501D02*
X72799D01*
G01X76287Y364801D02*
X73338D01*
G01X80200Y359049D02*
X75748Y363501D01*
G01X80739Y360349D02*
X76287Y364801D01*
G01X84922Y359049D02*
X80200D01*
G01X85461Y360349D02*
X80739D01*
G01X89145Y354826D02*
X84922Y359049D01*
G01X89684Y356126D02*
X85461Y360349D01*
G01X92358Y354826D02*
X89145D01*
G01X92897Y356126D02*
X89684D01*
G01X105709Y341475D02*
X92358Y354826D01*
G01X106248Y342775D02*
X92897Y356126D01*
G01X76287Y364801D02*
X73338D01*
G01X75748Y363501D02*
X72799D01*
G01X80739Y360349D02*
X76287Y364801D01*
G01X80200Y359049D02*
X75748Y363501D01*
G01X85461Y360349D02*
X80739D01*
G01X84922Y359049D02*
X80200D01*
G01X89684Y356126D02*
X85461Y360349D01*
G01X89145Y354826D02*
X84922Y359049D01*
G01X92897Y356126D02*
X89684D01*
G01X92358Y354826D02*
X89145D01*
G01X106248Y342775D02*
X92897Y356126D01*
G01X105709Y341475D02*
X92358Y354826D01*
G01X75748Y363501D02*
X72799D01*
G01X76287Y364801D02*
X73338D01*
G01X80200Y359049D02*
X75748Y363501D01*
G01X80739Y360349D02*
X76287Y364801D01*
G01X84922Y359049D02*
X80200D01*
G01X85461Y360349D02*
X80739D01*
G01X89145Y354826D02*
X84922Y359049D01*
G01X89684Y356126D02*
X85461Y360349D01*
G01X92358Y354826D02*
X89145D01*
G01X92897Y356126D02*
X89684D01*
G01X105709Y341475D02*
X92358Y354826D01*
G01X106248Y342775D02*
X92897Y356126D01*
G01X114626Y437026D02*
X96138Y449807D01*
G01X114626Y437026D02*
X96138Y449807D01*
G01X114626Y437026D02*
X96138Y449807D01*
G01X114626Y437026D02*
X96138Y449807D01*
G01X96878Y450877D02*
X105451Y444950D01*
G01X114626Y437026D02*
X96138Y449807D01*
G01X96877Y450877D02*
X96878D01*
G01X114626Y437026D02*
X96138Y449807D01*
G01X95031Y451631D02*
G02X96877Y450877I-788J-4567D01*
G01X96138Y449807D02*
G03X94810Y450349I-1894J-2744D01*
G01X92978Y451650D02*
X94801D01*
G01X94809Y450350D02*
X92978D01*
G01X94810Y450349D02*
X94809D01*
G01Y450350D02*
X92978D01*
G01Y451650D02*
X94801D01*
G01X94810Y450349D02*
X94809D01*
G01X92978Y451650D02*
X94801D01*
G01X96138Y449807D02*
G03X94810Y450349I-1894J-2744D01*
G01X95031Y451631D02*
G02X96877Y450877I-788J-4567D01*
G01X114626Y437026D02*
X96138Y449807D01*
G01X96878Y450877D02*
X105451Y444950D01*
G01X96877Y450877D02*
X96878D01*
G01X89688Y571226D02*
X97914Y563000D01*
G01X90988Y571765D02*
X98453Y564300D01*
G01X89688Y575883D02*
Y571226D01*
G01X90988Y576422D02*
Y571765D01*
G01X84571Y581000D02*
X89688Y575883D01*
G01X85110Y582300D02*
X90988Y576422D01*
G01X72716Y575125D02*
X78591Y581000D01*
G01X72177Y576425D02*
X78052Y582300D01*
G01X71748Y575125D02*
X72716D01*
G01X71209Y576425D02*
X72177D01*
G01X90988Y571765D02*
X98453Y564300D01*
G01X89688Y571226D02*
X97914Y563000D01*
G01X90988Y576422D02*
Y571765D01*
G01X89688Y575883D02*
Y571226D01*
G01X85110Y582300D02*
X90988Y576422D01*
G01X84571Y581000D02*
X89688Y575883D01*
G01X72177Y576425D02*
X78052Y582300D01*
G01X72716Y575125D02*
X78591Y581000D01*
G01X71209Y576425D02*
X72177D01*
G01X71748Y575125D02*
X72716D01*
G01X71748D02*
X72716D01*
G01X89688Y571226D02*
X97914Y563000D01*
G01X90988Y571765D02*
X98453Y564300D01*
G01X89688Y575883D02*
Y571226D01*
G01X90988Y576422D02*
Y571765D01*
G01X84571Y581000D02*
X89688Y575883D01*
G01X85110Y582300D02*
X90988Y576422D01*
G01X72716Y575125D02*
X78591Y581000D01*
G01X72177Y576425D02*
X78052Y582300D01*
G01X71748Y575125D02*
X72716D01*
G01X71209Y576425D02*
X72177D01*
G01X90988Y571765D02*
X98453Y564300D01*
G01X89688Y571226D02*
X97914Y563000D01*
G01X90988Y576422D02*
Y571765D01*
G01X89688Y575883D02*
Y571226D01*
G01X85110Y582300D02*
X90988Y576422D01*
G01X84571Y581000D02*
X89688Y575883D01*
G01X72177Y576425D02*
X78052Y582300D01*
G01X72716Y575125D02*
X78591Y581000D01*
G01X71209Y576425D02*
X72177D01*
G01X71748Y575125D02*
X72716D01*
G01X71748D02*
X72716D01*
G01X78591Y581000D02*
X84571D01*
G01X78052Y582300D02*
X85110D01*
G01X78052D02*
X85110D01*
G01X78591Y581000D02*
X84571D01*
G01X78591D02*
X84571D01*
G01X78052Y582300D02*
X85110D01*
G01X78052D02*
X85110D01*
G01X78591Y581000D02*
X84571D01*
G01X109691Y342775D02*
X106248D01*
G01X109152Y341475D02*
X105709D01*
G01X110791Y341675D02*
X109691Y342775D01*
G01X110252Y340375D02*
X109152Y341475D01*
G01X116052Y341675D02*
X110791D01*
G01X115513Y340375D02*
X110252D01*
G01X116702Y341025D02*
X116052Y341675D01*
G01X116163Y339725D02*
X115513Y340375D01*
G01X146725Y341025D02*
X116702D01*
G01X147264Y339725D02*
X116163D01*
G01X109152Y341475D02*
X105709D01*
G01X109691Y342775D02*
X106248D01*
G01X110252Y340375D02*
X109152Y341475D01*
G01X110791Y341675D02*
X109691Y342775D01*
G01X115513Y340375D02*
X110252D01*
G01X116052Y341675D02*
X110791D01*
G01X116163Y339725D02*
X115513Y340375D01*
G01X116702Y341025D02*
X116052Y341675D01*
G01X147264Y339725D02*
X116163D01*
G01X146725Y341025D02*
X116702D01*
G01X126983Y322971D02*
X132075Y321889D01*
G01X126983Y321641D02*
X132075Y320559D01*
G01X107423Y318812D02*
X126983Y322971D01*
G01X107423Y317482D02*
X126983Y321641D01*
G01X103948Y319551D02*
X107423Y318812D01*
G01X103442Y318329D02*
X107423Y317482D01*
G01X126983Y321641D02*
X132075Y320559D01*
G01X126983Y322971D02*
X132075Y321889D01*
G01X107423Y317482D02*
X126983Y321641D01*
G01X107423Y318812D02*
X126983Y322971D01*
G01X103442Y318329D02*
X107423Y317482D01*
G01X103948Y319551D02*
X107423Y318812D01*
G01X109691Y342775D02*
X106248D01*
G01X109152Y341475D02*
X105709D01*
G01X110791Y341675D02*
X109691Y342775D01*
G01X110252Y340375D02*
X109152Y341475D01*
G01X116052Y341675D02*
X110791D01*
G01X115513Y340375D02*
X110252D01*
G01X116702Y341025D02*
X116052Y341675D01*
G01X116163Y339725D02*
X115513Y340375D01*
G01X146725Y341025D02*
X116702D01*
G01X147264Y339725D02*
X116163D01*
G01X109152Y341475D02*
X105709D01*
G01X109691Y342775D02*
X106248D01*
G01X110252Y340375D02*
X109152Y341475D01*
G01X110791Y341675D02*
X109691Y342775D01*
G01X115513Y340375D02*
X110252D01*
G01X116052Y341675D02*
X110791D01*
G01X116163Y339725D02*
X115513Y340375D01*
G01X116702Y341025D02*
X116052Y341675D01*
G01X147264Y339725D02*
X116163D01*
G01X146725Y341025D02*
X116702D01*
G01X129505Y399457D02*
X164679Y391982D01*
G01X130023Y400676D02*
X147342Y396996D01*
G01X129505Y399457D02*
X164679Y391982D01*
G01X128185Y401917D02*
X130023Y400676D01*
G01X129068Y399752D02*
X129505Y399457D01*
G01X127248Y400981D02*
X129068Y399752D01*
G01X125285Y406217D02*
X128185Y401917D01*
G01X124277Y405386D02*
X127248Y400981D01*
G01X113518Y417984D02*
X125285Y406217D01*
G01X112671Y416992D02*
X124277Y405386D01*
G01X129505Y399457D02*
X164679Y391982D01*
G01X130023Y400676D02*
X147342Y396996D01*
G01X129068Y399752D02*
X129505Y399457D01*
G01X128185Y401917D02*
X130023Y400676D01*
G01X127248Y400981D02*
X129068Y399752D01*
G01X128185Y401917D02*
X130023Y400676D01*
G01X124277Y405386D02*
X127248Y400981D01*
G01X125285Y406217D02*
X128185Y401917D01*
G01X112671Y416992D02*
X124277Y405386D01*
G01X113518Y417984D02*
X125285Y406217D01*
G01X113518Y417984D02*
X125285Y406217D01*
G01X128618Y408262D02*
X133559Y405053D01*
G01X134065Y406275D02*
X129325Y409353D01*
G01X111511Y432525D02*
X128258Y408606D01*
G01X129325Y409353D02*
X112511Y433364D01*
G01X129325Y409353D02*
X112511Y433364D01*
G01X111511Y432525D02*
X128258Y408606D01*
G01X134065Y406275D02*
X129325Y409353D01*
G01X128618Y408262D02*
X133559Y405053D01*
G01X112598Y417064D02*
X112671Y416992D01*
G01X112598Y417064D02*
X112671Y416992D01*
G01X115561Y437958D02*
X132525Y413729D01*
G01X131603Y412777D02*
X114626Y437026D01*
G01X111826Y440543D02*
X115557Y437963D01*
G01X109317Y442277D02*
X110291Y442455D01*
G01X107960Y443215D02*
X109317Y442277D01*
G01X105451Y444950D02*
X106425Y445128D01*
G01X111826Y440543D02*
X115557Y437963D01*
G01X109317Y442277D02*
X110291Y442455D01*
G01X107960Y443215D02*
X109317Y442277D01*
G01X105451Y444950D02*
X106425Y445128D01*
G01X131603Y412777D02*
X114626Y437026D01*
G01X115561Y437958D02*
X132525Y413729D01*
G01X110718Y433318D02*
X111511Y432525D01*
G01X112511Y433364D02*
X111560Y434315D01*
G01X101665Y439587D02*
X110718Y433318D01*
G01X111558Y434318D02*
X102060Y440896D01*
G01X101384Y439785D02*
G02X101665Y439587I-1323J-2177D01*
G01X102060Y440896D02*
G03X100082Y441450I-1978J-3254D01*
G01Y440150D02*
G02X101384Y439785I-1J-2508D01*
G01X102060Y440896D02*
G03X100082Y441450I-1978J-3254D01*
G01X98129Y440150D02*
X100082D01*
G01Y441450D02*
X98129D01*
G01X100082D02*
X98129D01*
G01Y440150D02*
X100082D01*
G01X102060Y440896D02*
G03X100082Y441450I-1978J-3254D01*
G01X101384Y439785D02*
G02X101665Y439587I-1323J-2177D01*
G01X100082Y440150D02*
G02X101384Y439785I-1J-2508D01*
G01X111558Y434318D02*
X102060Y440896D01*
G01X101665Y439587D02*
X110718Y433318D01*
G01X112511Y433364D02*
X111560Y434315D01*
G01X110718Y433318D02*
X111511Y432525D01*
G01X97914Y563000D02*
X101210D01*
G01X98453Y564300D02*
X101430D01*
G01X98453D02*
X101430D01*
G01X97914Y563000D02*
X101210D01*
G01X97914D02*
X101210D01*
G01X98453Y564300D02*
X101430D01*
G01X98453D02*
X101430D01*
G01X97914Y563000D02*
X101210D01*
G01X148605Y342905D02*
X146725Y341025D01*
G01X149144Y341605D02*
X147264Y339725D01*
G01X169496Y342905D02*
X148605D01*
G01X168957Y341605D02*
X149144D01*
G01D02*
X147264Y339725D01*
G01X148605Y342905D02*
X146725Y341025D01*
G01X168957Y341605D02*
X149144D01*
G01X169496Y342905D02*
X148605D01*
G01X149364Y325556D02*
X168811Y321422D01*
G01X149364Y324226D02*
X168305Y320200D01*
G01X132075Y321889D02*
X149364Y325556D01*
G01X140989Y322449D02*
X149364Y324226D01*
G01X132075Y320559D02*
X140989Y322450D01*
G01X149364Y324226D02*
X168305Y320200D01*
G01X149364Y325556D02*
X168811Y321422D01*
G01X140989Y322449D02*
X149364Y324226D01*
G01X132075Y321889D02*
X149364Y325556D01*
G01X132075Y320559D02*
X140989Y322450D01*
G01X132075Y321889D02*
X149364Y325556D01*
G01X148605Y342905D02*
X146725Y341025D01*
G01X149144Y341605D02*
X147264Y339725D01*
G01X169496Y342905D02*
X148605D01*
G01X168957Y341605D02*
X149144D01*
G01D02*
X147264Y339725D01*
G01X148605Y342905D02*
X146725Y341025D01*
G01X168957Y341605D02*
X149144D01*
G01X169496Y342905D02*
X148605D01*
G01X164681Y393311D02*
X175969Y395670D01*
G01X164679Y391982D02*
X175967Y394341D01*
G01X147342Y396996D02*
X164681Y393311D01*
G01X164679Y391982D02*
X175967Y394341D01*
G01X164681Y393311D02*
X175969Y395670D01*
G01X147342Y396996D02*
X164681Y393311D01*
G01X157057Y409328D02*
X166247Y411281D01*
G01Y409951D02*
X157057Y407998D01*
G01X145364Y411814D02*
X157057Y409328D01*
G01Y407998D02*
X145364Y410484D01*
G01X139000Y410460D02*
X145364Y411814D01*
G01Y410484D02*
X139000Y409130D01*
G01X136822Y410923D02*
X139000Y410460D01*
G01Y409130D02*
X136314Y409701D01*
G01X133599Y413027D02*
X136822Y410923D01*
G01X136314Y409701D02*
X131603Y412777D01*
G01X136314Y409701D02*
X131603Y412777D01*
G01X136314Y409701D02*
X131603Y412777D01*
G01X133599Y413027D02*
X136822Y410923D01*
G01X139000Y409130D02*
X136314Y409701D01*
G01X136822Y410923D02*
X139000Y410460D01*
G01X145364Y410484D02*
X139000Y409130D01*
G01Y410460D02*
X145364Y411814D01*
G01X157057Y407998D02*
X145364Y410484D01*
G01Y411814D02*
X157057Y409328D01*
G01X166247Y409951D02*
X157057Y407998D01*
G01Y409328D02*
X166247Y411281D01*
G01X160394Y401171D02*
X167249Y402629D01*
G01Y403959D02*
X160394Y402501D01*
G01X158080Y401663D02*
X160394Y401171D01*
G01Y402501D02*
X158586Y402885D01*
G01X153927Y404360D02*
X158080Y401663D01*
G01X158586Y402885D02*
X154433Y405582D01*
G01X145324Y406188D02*
X153927Y404360D01*
G01X154433Y405582D02*
X145324Y407518D01*
G01X136769Y404370D02*
X145324Y406188D01*
G01Y407518D02*
X136769Y405700D01*
G01X133559Y405053D02*
X136769Y404370D01*
G01Y405700D02*
X134065Y406275D01*
G01X136769Y405700D02*
X134065Y406275D01*
G01X133559Y405053D02*
X136769Y404370D01*
G01X145324Y407518D02*
X136769Y405700D01*
G01Y404370D02*
X145324Y406188D01*
G01X154433Y405582D02*
X145324Y407518D01*
G01Y406188D02*
X153927Y404360D01*
G01X158586Y402885D02*
X154433Y405582D01*
G01X153927Y404360D02*
X158080Y401663D01*
G01X160394Y402501D02*
X158586Y402885D01*
G01X158080Y401663D02*
X160394Y401171D01*
G01X167249Y403959D02*
X160394Y402501D01*
G01Y401171D02*
X167249Y402629D01*
G01X132525Y413729D02*
X133599Y413027D01*
G01X132525Y413729D02*
X133599Y413027D01*
G01X193605Y310044D02*
X204406Y312337D01*
G01X179244Y313098D02*
X193605Y310044D01*
G01D02*
X204406Y312337D01*
G01X179244Y313098D02*
X193605Y310044D01*
G01X174076Y338325D02*
X169496Y342905D01*
G01X173537Y337025D02*
X168957Y341605D01*
G01X219682Y338325D02*
X174076D01*
G01X219682Y337025D02*
X173537D01*
G01D02*
X168957Y341605D01*
G01X174076Y338325D02*
X169496Y342905D01*
G01X219682Y337025D02*
X173537D01*
G01X219682Y338325D02*
X174076D01*
G01X193605Y311374D02*
X222092Y317426D01*
G01X179750Y314320D02*
X193605Y311374D01*
G01X168811Y321422D02*
X179750Y314320D01*
G01X168305Y320200D02*
X179244Y313098D01*
G01X193605Y311374D02*
X222092Y317426D01*
G01X193605Y311374D02*
X222092Y317426D01*
G01X193605Y311374D02*
X222092Y317426D01*
G01X179750Y314320D02*
X193605Y311374D01*
G01X168305Y320200D02*
X179244Y313098D01*
G01X168811Y321422D02*
X179750Y314320D01*
G01X174076Y338325D02*
X169496Y342905D01*
G01X173537Y337025D02*
X168957Y341605D01*
G01X219682Y338325D02*
X174076D01*
G01X219682Y337025D02*
X173537D01*
G01D02*
X168957Y341605D01*
G01X174076Y338325D02*
X169496Y342905D01*
G01X219682Y337025D02*
X173537D01*
G01X219682Y338325D02*
X174076D01*
G01X175969Y395670D02*
X203271Y389866D01*
G01X175969Y394340D02*
X203248Y388541D01*
G01X175969Y394340D02*
X203248Y388541D01*
G01X175969Y395670D02*
X203271Y389866D01*
G01X193701Y401611D02*
X200898Y400115D01*
G01X200878Y398791D02*
X177825Y403581D01*
G01X189099Y402567D02*
X190714Y402231D01*
G01X200878Y398791D02*
X177825Y403581D01*
G01X178329Y404805D02*
X186113Y403188D01*
G01X200878Y398791D02*
X177825Y403581D01*
G01X173854Y407710D02*
X178329Y404805D01*
G01X177825Y403581D02*
X168875Y409393D01*
G01X169381Y410615D02*
X173854Y407710D01*
G01X177825Y403581D02*
X168875Y409393D01*
G01X167831Y410944D02*
X169381Y410615D01*
G01X168875Y409393D02*
X166247Y409951D01*
G01Y411281D02*
X167831Y410944D01*
G01X168875Y409393D02*
X166247Y409951D01*
G01X168875Y409393D02*
X166247Y409951D01*
G01X167831Y410944D02*
X169381Y410615D01*
G01X166247Y411281D02*
X167831Y410944D01*
G01X177825Y403581D02*
X168875Y409393D01*
G01X173854Y407710D02*
X178329Y404805D01*
G01X169381Y410615D02*
X173854Y407710D01*
G01X200878Y398791D02*
X177825Y403581D01*
G01X193701Y401611D02*
X200898Y400115D01*
G01X189099Y402567D02*
X190714Y402231D01*
G01X178329Y404805D02*
X186113Y403188D01*
G01X174400Y399535D02*
X200365Y394016D01*
G01X200392Y395340D02*
X174906Y400757D01*
G01X170796Y401875D02*
X174400Y399535D01*
G01X174906Y400757D02*
X171302Y403097D01*
G01X167249Y402629D02*
X170796Y401875D01*
G01X171302Y403097D02*
X167249Y403959D01*
G01X171302Y403097D02*
X167249Y403959D01*
G01Y402629D02*
X170796Y401875D01*
G01X174906Y400757D02*
X171302Y403097D01*
G01X170796Y401875D02*
X174400Y399535D01*
G01X200392Y395340D02*
X174906Y400757D01*
G01X174400Y399535D02*
X200365Y394016D01*
G01X198370Y812665D02*
G03X199483Y809978I3800J0D01*
G01X198370Y819407D02*
Y812665D01*
G01D02*
G03X199483Y809978I3800J0D01*
G01X198370Y819407D02*
Y812665D01*
G01X198100Y866452D02*
Y869547D01*
G01X210700Y846495D02*
X198100Y866452D01*
G01D02*
Y869547D01*
G01X210700Y846495D02*
X198100Y866452D01*
G01X222092Y317426D02*
X233836Y314930D01*
G01X222092Y316096D02*
X233836Y313600D01*
G01X204407Y312337D02*
X222092Y316096D01*
G01X204406Y312337D02*
X204407D01*
G01X222092Y316096D02*
X233836Y313600D01*
G01X222092Y317426D02*
X233836Y314930D01*
G01X204407Y312337D02*
X222092Y316096D01*
G01X204406Y312337D02*
X204407D01*
G01X203271Y389866D02*
X236383Y395707D01*
G01X203248Y388541D02*
X236383Y394386D01*
G01X203248Y388541D02*
X236383Y394386D01*
G01X203271Y389866D02*
X236383Y395707D01*
G01X220296Y403536D02*
X232902Y412364D01*
G01X227345Y406884D02*
X220806Y402305D01*
G01X233412Y411133D02*
X227345Y406884D01*
G01X200898Y400115D02*
X220293Y403533D01*
G01X220806Y402303D02*
X200878Y398791D01*
G01X220806Y402303D02*
X200878Y398791D01*
G01X200898Y400115D02*
X220293Y403533D01*
G01X227345Y406884D02*
X220806Y402305D01*
G01X220296Y403536D02*
X232902Y412364D01*
G01X233412Y411133D02*
X227345Y406884D01*
G01X220296Y403536D02*
X232902Y412364D01*
G01X224494Y398138D02*
X236113Y406271D01*
G01X235603Y407502D02*
X223984Y399369D01*
G01X200365Y394016D02*
X224494Y398138D01*
G01X223984Y399371D02*
X200392Y395340D01*
G01X223984Y399371D02*
X200392Y395340D01*
G01X200365Y394016D02*
X224494Y398138D01*
G01X235603Y407502D02*
X223984Y399369D01*
G01X224494Y398138D02*
X236113Y406271D01*
G01X220631Y790669D02*
X263575Y760599D01*
G01X219792Y789669D02*
X263065Y759368D01*
G01X219792Y789669D02*
X263065Y759368D01*
G01X220631Y790669D02*
X263575Y760599D01*
G01X238160Y795652D02*
X223302Y816872D01*
G01X239094Y796586D02*
X224602Y817282D01*
G01X233578Y788950D02*
X212000Y819765D01*
G01X232644Y788016D02*
X210700Y819354D01*
G01X239094Y796586D02*
X224602Y817282D01*
G01X238160Y795652D02*
X223302Y816872D01*
G01X200402Y810898D02*
X220631Y790669D01*
G01X199483Y809978D02*
X219792Y789669D01*
G01X199670Y812666D02*
G03X200402Y810898I2500J0D01*
G01X199670Y819600D02*
Y812666D01*
G01X232644Y788016D02*
X210700Y819354D01*
G01X233578Y788950D02*
X212000Y819765D01*
G01X199483Y809978D02*
X219792Y789669D01*
G01X200402Y810898D02*
X220631Y790669D01*
G01X199670Y812666D02*
G03X200402Y810898I2500J0D01*
G01X199670Y819600D02*
Y812666D01*
G01X234953Y846463D02*
X223365Y863014D01*
G01X234953Y846463D02*
X223365Y863014D01*
G01X223300Y844715D02*
X210767Y866134D01*
G01X224600Y845068D02*
X212067Y866487D01*
G01X212000Y846872D02*
X199400Y866829D01*
G01X212000Y819765D02*
Y846872D01*
G01X210700Y819354D02*
Y846495D01*
G01X224600Y845068D02*
X212067Y866487D01*
G01X223300Y844715D02*
X210767Y866134D01*
G01X212000Y846872D02*
X199400Y866829D01*
G01X210700Y819354D02*
Y846495D01*
G01X212000Y819765D02*
Y846872D01*
G01X224665Y863424D02*
Y872882D01*
G01X223365Y863014D02*
Y872882D01*
G01X236184Y846973D02*
X224665Y863424D01*
G01X223365Y863014D02*
Y872882D01*
G01X224665Y863424D02*
Y872882D01*
G01X236184Y846973D02*
X224665Y863424D01*
G01X210767Y866134D02*
Y872882D01*
G01X212067Y866487D02*
Y872900D01*
G01X199400Y866829D02*
Y870219D01*
G01X212067Y866487D02*
Y872900D01*
G01X210767Y866134D02*
Y872882D01*
G01X199400Y866829D02*
Y870219D01*
G01X262637Y321052D02*
X291858Y314841D01*
G01X262637Y319722D02*
X291858Y313511D01*
G01X233836Y314930D02*
X262637Y321052D01*
G01X233836Y313600D02*
X262637Y319722D01*
G01D02*
X291858Y313511D01*
G01X262637Y321052D02*
X291858Y314841D01*
G01X233836Y313600D02*
X262637Y319722D01*
G01X233836Y314930D02*
X262637Y321052D01*
G01X250832Y393158D02*
X327946Y406777D01*
G01X250832Y391837D02*
X327946Y405456D01*
G01X236383Y395707D02*
X250832Y393158D01*
G01X236383Y394386D02*
X250832Y391837D01*
G01D02*
X327946Y405456D01*
G01X250832Y393158D02*
X327946Y406777D01*
G01X236383Y394386D02*
X250832Y391837D01*
G01X236383Y395707D02*
X250832Y393158D01*
G01X247421Y414922D02*
X273429Y409396D01*
G01Y408066D02*
X247398Y413597D01*
G01D02*
X233412Y411133D01*
G01X247398Y413597D02*
X233412Y411133D01*
G01X273429Y408066D02*
X247398Y413597D01*
G01X247421Y414922D02*
X273429Y409396D01*
G01X249009Y408544D02*
X274633Y403098D01*
G01Y404428D02*
X249032Y409869D01*
G01X236113Y406271D02*
X249009Y408544D01*
G01X249032Y409869D02*
X235603Y407502D01*
G01X249032Y409869D02*
X235603Y407502D01*
G01X236113Y406271D02*
X249009Y408544D01*
G01X274633Y404428D02*
X249032Y409869D01*
G01X249009Y408544D02*
X274633Y403098D01*
G01X232902Y412364D02*
X247421Y414922D01*
G01X232902Y412364D02*
X247421Y414922D01*
G01X257153Y782352D02*
X238160Y795652D01*
G01X267474Y780533D02*
X257153Y782352D01*
G01X267984Y781764D02*
X257663Y783583D01*
G01X269281Y763949D02*
X233578Y788950D01*
G01X268771Y762718D02*
X232644Y788016D01*
G01X257153Y782352D02*
X238160Y795652D01*
G01X267984Y781764D02*
X257663Y783583D01*
G01X267474Y780533D02*
X257153Y782352D01*
G01X263575Y760599D02*
X285800Y756680D01*
G01X263065Y759368D02*
X285290Y755449D01*
G01X268771Y762718D02*
X232644Y788016D01*
G01X269281Y763949D02*
X233578Y788950D01*
G01X263065Y759368D02*
X285290Y755449D01*
G01X263575Y760599D02*
X285800Y756680D01*
G01X250366Y805666D02*
X242054Y817536D01*
G01X243285Y818046D02*
X251300Y806600D01*
G01X273133Y789724D02*
X250366Y805666D01*
G01X251300Y806600D02*
X273643Y790955D01*
G01X258200Y814874D02*
Y834386D01*
G01X259500Y815284D02*
Y834500D01*
G01X261566Y810066D02*
X258200Y814874D01*
G01X262500Y811000D02*
X259500Y815284D01*
G01X280308Y796943D02*
X261566Y810066D01*
G01X280818Y798174D02*
X262500Y811000D01*
G01X251300Y806600D02*
X273643Y790955D01*
G01X273133Y789724D02*
X250366Y805666D01*
G01X243285Y818046D02*
X251300Y806600D01*
G01X250366Y805666D02*
X242054Y817536D01*
G01X259500Y815284D02*
Y834500D01*
G01X258200Y814874D02*
Y834386D01*
G01X262500Y811000D02*
X259500Y815284D01*
G01X261566Y810066D02*
X258200Y814874D01*
G01X280818Y798174D02*
X262500Y811000D01*
G01X280308Y796943D02*
X261566Y810066D01*
G01X239268Y810927D02*
X237364Y821721D01*
G01X238037Y810417D02*
X236043Y821721D01*
G01X249300Y796600D02*
X239268Y810927D01*
G01X248366Y795666D02*
X238037Y810417D01*
G01X260643Y788658D02*
X249300Y796600D01*
G01X260133Y787427D02*
X248366Y795666D01*
G01X346592Y773503D02*
X260643Y788658D01*
G01X346082Y772272D02*
X260133Y787427D01*
G01X238037Y810417D02*
X236043Y821721D01*
G01X239268Y810927D02*
X237364Y821721D01*
G01X248366Y795666D02*
X238037Y810417D01*
G01X249300Y796600D02*
X239268Y810927D01*
G01X260133Y787427D02*
X248366Y795666D01*
G01X260643Y788658D02*
X249300Y796600D01*
G01X346082Y772272D02*
X260133Y787427D01*
G01X346592Y773503D02*
X260643Y788658D01*
G01X257663Y783583D02*
X239094Y796586D01*
G01X257663Y783583D02*
X239094Y796586D01*
G01X242179Y831000D02*
X235963Y866258D01*
G01X237263Y866376D02*
X243500Y831000D01*
G01X240930Y823914D02*
X242179Y831000D01*
G01X243500D02*
X242251Y823914D01*
G01X242054Y817536D02*
X240930Y823914D01*
G01X242251D02*
X243285Y818046D01*
G01X259144Y849475D02*
X256537Y864261D01*
G01X260465Y849475D02*
X257858Y864261D01*
G01X257342Y839249D02*
X259144Y849475D01*
G01X258663Y839249D02*
X260465Y849475D01*
G01X258200Y834386D02*
X257342Y839249D01*
G01X259500Y834500D02*
X258663Y839249D01*
G01X242251Y823914D02*
X243285Y818046D01*
G01X242054Y817536D02*
X240930Y823914D01*
G01X243500Y831000D02*
X242251Y823914D01*
G01X240930D02*
X242179Y831000D01*
G01X237263Y866376D02*
X243500Y831000D01*
G01X242179D02*
X235963Y866258D01*
G01X260465Y849475D02*
X257858Y864261D01*
G01X259144Y849475D02*
X256537Y864261D01*
G01X258663Y839249D02*
X260465Y849475D01*
G01X257342Y839249D02*
X259144Y849475D01*
G01X259500Y834500D02*
X258663Y839249D01*
G01X258200Y834386D02*
X257342Y839249D01*
G01X239000Y831000D02*
X236184Y846973D01*
G01X237679Y831000D02*
X234953Y846463D01*
G01X238142Y826136D02*
X239000Y831000D01*
G01X236043Y821721D02*
X237679Y831000D01*
G01X237364Y821721D02*
X238142Y826136D01*
G01X236043Y821721D02*
X237679Y831000D01*
G01D02*
X234953Y846463D01*
G01X239000Y831000D02*
X236184Y846973D01*
G01X236043Y821721D02*
X237679Y831000D01*
G01X238142Y826136D02*
X239000Y831000D01*
G01X237364Y821721D02*
X238142Y826136D01*
G01X235963Y866258D02*
Y872882D01*
G01X237263D02*
Y866376D01*
G01X258011Y872614D02*
Y872882D01*
G01X259311Y872500D02*
Y872882D01*
G01X256537Y864261D02*
X258011Y872614D01*
G01X257858Y864261D02*
X259311Y872500D01*
G01X237263Y872882D02*
Y866376D01*
G01X235963Y866258D02*
Y872882D01*
G01X259311Y872500D02*
Y872882D01*
G01X258011Y872614D02*
Y872882D01*
G01X257858Y864261D02*
X259311Y872500D01*
G01X256537Y864261D02*
X258011Y872614D01*
G01X299364Y316437D02*
X302711Y318610D01*
G01X299870Y315215D02*
X303217Y317388D01*
G01X291858Y314841D02*
X299364Y316437D01*
G01X291858Y313511D02*
X299870Y315215D01*
G01D02*
X303217Y317388D01*
G01X299364Y316437D02*
X302711Y318610D01*
G01X291858Y313511D02*
X299870Y315215D01*
G01X291858Y314841D02*
X299364Y316437D01*
G01X273429Y409396D02*
X298054Y414630D01*
G01Y413300D02*
X273429Y408066D01*
G01X298054Y413300D02*
X273429Y408066D01*
G01Y409396D02*
X298054Y414630D01*
G01X298631Y408199D02*
X308065Y406194D01*
G01Y407524D02*
X298631Y409529D01*
G01X274633Y403098D02*
X298631Y408199D01*
G01Y409529D02*
X274633Y404428D01*
G01X298631Y409529D02*
X274633Y404428D01*
G01Y403098D02*
X298631Y408199D01*
G01X308065Y407524D02*
X298631Y409529D01*
G01Y408199D02*
X308065Y406194D01*
G01X298054Y414630D02*
X308926Y412319D01*
G01Y410989D02*
X298054Y413300D01*
G01X308926Y410989D02*
X298054Y413300D01*
G01Y414630D02*
X308926Y412319D01*
G01X294500Y749000D02*
X303585Y747398D01*
G01X285290Y755449D02*
X294500Y749000D01*
G01D02*
X303585Y747398D01*
G01X285290Y755449D02*
X294500Y749000D01*
G01X279990Y771769D02*
X267474Y780533D01*
G01X280500Y773000D02*
X267984Y781764D01*
G01X298506Y768504D02*
X279990Y771769D01*
G01X298506Y769825D02*
X280500Y773000D01*
G01X315827Y771558D02*
X298506Y768504D01*
G01X315827Y772879D02*
X298506Y769825D01*
G01X298206Y758849D02*
X269281Y763949D01*
G01X298206Y757528D02*
X268771Y762718D01*
G01X323829Y763367D02*
X298206Y758849D01*
G01X323829Y762046D02*
X298206Y757528D01*
G01X280500Y773000D02*
X267984Y781764D01*
G01X279990Y771769D02*
X267474Y780533D01*
G01X298506Y769825D02*
X280500Y773000D01*
G01X298506Y768504D02*
X279990Y771769D01*
G01X315827Y772879D02*
X298506Y769825D01*
G01X315827Y771558D02*
X298506Y768504D01*
G01X295010Y750231D02*
X303585Y748719D01*
G01X285800Y756680D02*
X295010Y750231D01*
G01X298206Y757528D02*
X268771Y762718D01*
G01X298206Y758849D02*
X269281Y763949D01*
G01X323829Y762046D02*
X298206Y757528D01*
G01X323829Y763367D02*
X298206Y758849D01*
G01X295010Y750231D02*
X303585Y748719D01*
G01X285800Y756680D02*
X295010Y750231D01*
G01X284726Y805402D02*
X344794Y794814D01*
G01X285236Y806633D02*
X345305Y796044D01*
G01X275424Y811916D02*
X284726Y805402D01*
G01X276358Y812850D02*
X285236Y806633D01*
G01X271694Y817242D02*
X275424Y811916D01*
G01X272925Y817752D02*
X276358Y812850D01*
G01X285236Y806633D02*
X345305Y796044D01*
G01X284726Y805402D02*
X344794Y794814D01*
G01X276358Y812850D02*
X285236Y806633D01*
G01X275424Y811916D02*
X284726Y805402D01*
G01X272925Y817752D02*
X276358Y812850D01*
G01X271694Y817242D02*
X275424Y811916D01*
G01X348506Y776435D02*
X273133Y789724D01*
G01X273643Y790955D02*
X349016Y777666D01*
G01X342872Y785909D02*
X280308Y796943D01*
G01X343382Y787140D02*
X280818Y798174D01*
G01X273643Y790955D02*
X349016Y777666D01*
G01X348506Y776435D02*
X273133Y789724D01*
G01X343382Y787140D02*
X280818Y798174D01*
G01X342872Y785909D02*
X280308Y796943D01*
G01X299714Y816610D02*
X331238Y811053D01*
G01X289066Y824066D02*
X299714Y816610D01*
G01X290000Y825000D02*
X300224Y817841D01*
G01X287360Y826503D02*
X289066Y824066D01*
G01X288591Y827013D02*
X290000Y825000D01*
G01X282977Y851357D02*
X287360Y826503D01*
G01X284298Y851357D02*
X288591Y827013D01*
G01X299714Y816610D02*
X331238Y811053D01*
G01X290000Y825000D02*
X300224Y817841D01*
G01X289066Y824066D02*
X299714Y816610D01*
G01X288591Y827013D02*
X290000Y825000D01*
G01X287360Y826503D02*
X289066Y824066D01*
G01X284298Y851357D02*
X288591Y827013D01*
G01X282977Y851357D02*
X287360Y826503D01*
G01X270700Y822886D02*
X271694Y817242D01*
G01X272000Y823000D02*
X272925Y817752D01*
G01X270700Y845279D02*
Y822886D01*
G01X272000Y845165D02*
Y823000D01*
G01X272237Y853999D02*
X270700Y845279D01*
G01X273558Y853999D02*
X272000Y845165D01*
G01Y823000D02*
X272925Y817752D01*
G01X270700Y822886D02*
X271694Y817242D01*
G01X272000Y845165D02*
Y823000D01*
G01X270700Y845279D02*
Y822886D01*
G01X273558Y853999D02*
X272000Y845165D01*
G01X272237Y853999D02*
X270700Y845279D01*
G01X283665Y855251D02*
X282977Y851357D01*
G01X284986Y855251D02*
X284298Y851357D01*
G01X283250Y857609D02*
X283665Y855251D01*
G01X284550Y857723D02*
X284986Y855251D01*
G01X283250Y863906D02*
Y857609D01*
G01X284550Y863906D02*
Y857723D01*
G01X284986Y855251D02*
X284298Y851357D01*
G01X283665Y855251D02*
X282977Y851357D01*
G01X284550Y857723D02*
X284986Y855251D01*
G01X283250Y857609D02*
X283665Y855251D01*
G01X284550Y863906D02*
Y857723D01*
G01X283250Y863906D02*
Y857609D01*
G01X270609Y863238D02*
X272237Y853999D01*
G01X271909Y863352D02*
X273558Y853999D01*
G01X270609Y872882D02*
Y863238D01*
G01X271909Y872882D02*
Y863352D01*
G01D02*
X273558Y853999D01*
G01X270609Y863238D02*
X272237Y853999D01*
G01X271909Y872882D02*
Y863352D01*
G01X270609Y872882D02*
Y863238D01*
G01X312265Y318997D02*
X335466Y303934D01*
G01X311759Y317775D02*
X335081Y302634D01*
G01X311759Y317775D02*
X335081Y302634D01*
G01X312265Y318997D02*
X335466Y303934D01*
G01X308399Y319819D02*
X312265Y318997D01*
G01X308399Y318489D02*
X311759Y317775D01*
G01X302711Y318610D02*
X308399Y319819D01*
G01X303217Y317388D02*
X308399Y318489D01*
G01D02*
X311759Y317775D01*
G01X308399Y319819D02*
X312265Y318997D01*
G01X303217Y317388D02*
X308399Y318489D01*
G01X302711Y318610D02*
X308399Y319819D01*
G01X327946Y406777D02*
X342840Y404148D01*
G01X327946Y405456D02*
X342840Y402827D01*
G01X327946Y405456D02*
X342840Y402827D01*
G01X327946Y406777D02*
X342840Y404148D01*
G01X328034Y415050D02*
X308926Y410989D01*
G01X328034Y415050D02*
X308926Y410989D01*
G01X328696Y410579D02*
X344984Y407116D01*
G01X345007Y408441D02*
X328696Y411909D01*
G01X308065Y406194D02*
X328696Y410579D01*
G01Y411909D02*
X308065Y407524D01*
G01X328696Y411909D02*
X308065Y407524D01*
G01Y406194D02*
X328696Y410579D01*
G01X345007Y408441D02*
X328696Y411909D01*
G01Y410579D02*
X344984Y407116D01*
G01X328034Y416380D02*
X343962Y412995D01*
G01X335986Y413361D02*
X328034Y415050D01*
G01X308926Y412319D02*
X328034Y416380D01*
G01X308926Y412319D02*
X328034Y416380D01*
G01X335986Y413361D02*
X328034Y415050D01*
G01Y416380D02*
X343962Y412995D01*
G01X328034Y416380D02*
X343962Y412995D01*
G01X320128Y748858D02*
X344136Y753092D01*
G01X320128Y747537D02*
X344136Y751771D01*
G01X312248Y750246D02*
X320128Y748858D01*
G01X312248Y748925D02*
X320128Y747537D01*
G01X303585Y748719D02*
X312248Y750246D01*
G01X303585Y747398D02*
X312248Y748925D01*
G01X320128Y747537D02*
X344136Y751771D01*
G01X320128Y748858D02*
X344136Y753092D01*
G01X312248Y748925D02*
X320128Y747537D01*
G01X312248Y750246D02*
X320128Y748858D01*
G01X303585Y747398D02*
X312248Y748925D01*
G01X303585Y748719D02*
X312248Y750246D01*
G01X345272Y766366D02*
X315827Y771558D01*
G01X345782Y767597D02*
X315827Y772879D01*
G01X347620Y759172D02*
X323829Y763367D01*
G01X347110Y757941D02*
X323829Y762046D01*
G01X345782Y767597D02*
X315827Y772879D01*
G01X345272Y766366D02*
X315827Y771558D01*
G01X347110Y757941D02*
X323829Y762046D01*
G01X347620Y759172D02*
X323829Y763367D01*
G01X324713Y820632D02*
X389066Y775566D01*
G01X325460Y821698D02*
X390000Y776500D01*
G01X325460Y821698D02*
X390000Y776500D01*
G01X324713Y820632D02*
X389066Y775566D01*
G01X324713Y820632D02*
X389066Y775566D01*
G01X324713Y820632D02*
X389066Y775566D01*
G01X331238Y811053D02*
X385539Y773033D01*
G01X331748Y812284D02*
X386473Y773967D01*
G01X300224Y817841D02*
X331748Y812284D01*
G01D02*
X386473Y773967D01*
G01X331238Y811053D02*
X385539Y773033D01*
G01X300224Y817841D02*
X331748Y812284D01*
G01X333700Y822590D02*
X336752Y818229D01*
G01X333700Y836886D02*
Y822590D01*
G01X331561Y849011D02*
X333700Y836886D01*
G01X333502Y845499D02*
X333912Y843174D01*
G01X332792Y849521D02*
X333502Y845499D01*
G01X321003Y864090D02*
X331561Y849011D01*
G01X322303Y864500D02*
X332792Y849521D01*
G01X333700Y822590D02*
X336752Y818229D01*
G01X333700Y836886D02*
Y822590D01*
G01X331561Y849011D02*
X333700Y836886D01*
G01X333502Y845499D02*
X333912Y843174D01*
G01X331561Y849011D02*
X333700Y836886D01*
G01X332792Y849521D02*
X333502Y845499D01*
G01X331561Y849011D02*
X333700Y836886D01*
G01X322303Y864500D02*
X332792Y849521D01*
G01X321003Y864090D02*
X331561Y849011D01*
G01X325459Y821698D02*
X325460D01*
G01X325227Y821860D02*
X325459Y821698D01*
G01X312009Y822970D02*
X324713Y820632D01*
G01X325459Y821698D02*
X325460D01*
G01X325227Y821860D02*
X325459Y821698D01*
G01X312523Y824198D02*
X325227Y821860D01*
G01X306269Y826990D02*
X312009Y822970D01*
G01X307457Y827747D02*
X312518Y824202D01*
G01X305121Y833500D02*
X306269Y826990D01*
G01X306442Y833500D02*
X307457Y827747D01*
G01X308705Y853821D02*
X305121Y833500D01*
G01X310005Y853707D02*
X306442Y833500D01*
G01X325459Y821698D02*
X325460D01*
G01X312009Y822970D02*
X324713Y820632D01*
G01X325227Y821860D02*
X325459Y821698D01*
G01X312009Y822970D02*
X324713Y820632D01*
G01X312523Y824198D02*
X325227Y821860D01*
G01X312009Y822970D02*
X324713Y820632D01*
G01X307457Y827747D02*
X312518Y824202D01*
G01X306269Y826990D02*
X312009Y822970D01*
G01X306442Y833500D02*
X307457Y827747D01*
G01X305121Y833500D02*
X306269Y826990D01*
G01X310005Y853707D02*
X306442Y833500D01*
G01X308705Y853821D02*
X305121Y833500D01*
G01X333601Y867944D02*
Y872882D01*
G01X334683Y861806D02*
X333601Y867944D01*
G01D02*
Y872882D01*
G01X334683Y861806D02*
X333601Y867944D01*
G01X321003Y872882D02*
Y864090D01*
G01X322303Y872882D02*
Y864500D01*
G01Y872882D02*
Y864500D01*
G01X321003Y872882D02*
Y864090D01*
G01X308705Y863382D02*
Y853821D01*
G01X310005Y863382D02*
Y853707D01*
G01Y863382D02*
Y853707D01*
G01X308705Y863382D02*
Y853821D01*
G01X335466Y303934D02*
X340552D01*
G01X335081Y302634D02*
X340552D01*
G01X335081D02*
X340552D01*
G01X335466Y303934D02*
X340552D01*
G01X342840Y402827D02*
X459339Y423328D01*
G01X342840Y404148D02*
X459346Y424650D01*
G01X342840Y402827D02*
X459339Y423328D01*
G01X342840Y404148D02*
X459346Y424650D01*
G01X342840Y402827D02*
X459339Y423328D01*
G01X342840Y404148D02*
X459346Y424650D01*
G01X344984Y407116D02*
X462530Y427844D01*
G01X462553Y429169D02*
X345007Y408441D01*
G01X462553Y429169D02*
X345007Y408441D01*
G01X344984Y407116D02*
X462530Y427844D01*
G01X343962Y412995D02*
X462227Y433847D01*
G01X462204Y432522D02*
X343939Y411670D01*
G01D02*
X335986Y413361D01*
G01X343939Y411670D02*
X335986Y413361D01*
G01X462204Y432522D02*
X343939Y411670D01*
G01X343962Y412995D02*
X462227Y433847D01*
G01X375000Y740000D02*
X347620Y759172D01*
G01X374066Y739066D02*
X347110Y757941D01*
G01X347542Y752491D02*
X372867Y734757D01*
G01X347032Y751260D02*
X371933Y733823D01*
G01X374066Y739066D02*
X347110Y757941D01*
G01X375000Y740000D02*
X347620Y759172D01*
G01X347032Y751260D02*
X371933Y733823D01*
G01X347542Y752491D02*
X372867Y734757D01*
G01X344794Y794814D02*
X381566Y769066D01*
G01X345305Y796044D02*
X382500Y770000D01*
G01X345305Y796044D02*
X382500Y770000D01*
G01X344794Y794814D02*
X381566Y769066D01*
G01X384166Y751466D02*
X348506Y776435D01*
G01X349016Y777666D02*
X385100Y752400D01*
G01X385794Y755855D02*
X342872Y785909D01*
G01X386728Y756789D02*
X343382Y787140D01*
G01X349016Y777666D02*
X385100Y752400D01*
G01X384166Y751466D02*
X348506Y776435D01*
G01X386728Y756789D02*
X343382Y787140D01*
G01X385794Y755855D02*
X342872Y785909D01*
G01X382300Y748500D02*
X346592Y773503D01*
G01X381366Y747566D02*
X346082Y772272D01*
G01X381366Y747566D02*
X346082Y772272D01*
G01X382300Y748500D02*
X346592Y773503D01*
G01X377593Y743735D02*
X345272Y766366D01*
G01X378527Y744669D02*
X345782Y767597D01*
G01X378527Y744669D02*
X345782Y767597D01*
G01X377593Y743735D02*
X345272Y766366D01*
G01X344136Y753092D02*
X347542Y752491D01*
G01X344136Y751771D02*
X347032Y751260D01*
G01X344136Y751771D02*
X347032Y751260D01*
G01X344136Y753092D02*
X347542Y752491D01*
G01X364903Y809731D02*
X398045Y786524D01*
G01X365837Y810665D02*
X398979Y787458D01*
G01X358700Y818590D02*
X364903Y809731D01*
G01X360000Y819000D02*
X365837Y810665D01*
G01X351179Y814684D02*
X347471Y819980D01*
G01X350245Y813750D02*
X346171Y819570D01*
G01X395000Y784000D02*
X351179Y814684D01*
G01X394066Y783066D02*
X350245Y813750D01*
G01X365837Y810665D02*
X398979Y787458D01*
G01X364903Y809731D02*
X398045Y786524D01*
G01X360000Y819000D02*
X365837Y810665D01*
G01X358700Y818590D02*
X364903Y809731D01*
G01X350245Y813750D02*
X346171Y819570D01*
G01X351179Y814684D02*
X347471Y819980D01*
G01X394066Y783066D02*
X350245Y813750D01*
G01X395000Y784000D02*
X351179Y814684D01*
G01X336752Y818229D02*
X391169Y780134D01*
G01X337686Y819163D02*
X392103Y781068D01*
G01X337686Y819163D02*
X392103Y781068D01*
G01X336752Y818229D02*
X391169Y780134D01*
G01X370781Y844763D02*
X359769Y860490D01*
G01X370781Y844763D02*
X359769Y860490D01*
G01X358700Y841386D02*
Y818590D01*
G01X360000Y841500D02*
Y819000D01*
G01X357396Y848777D02*
X358700Y841386D01*
G01X358627Y849287D02*
X360000Y841500D01*
G01X347692Y862636D02*
X357396Y848777D01*
G01X348923Y863146D02*
X358627Y849287D01*
G01X346220Y847597D02*
X335914Y862316D01*
G01X344989Y847087D02*
X334683Y861806D01*
G01X347471Y840500D02*
X346220Y847597D01*
G01X346171Y840386D02*
X344989Y847087D01*
G01X347471Y819980D02*
Y840500D01*
G01X346171Y819570D02*
Y840386D01*
G01X360000Y841500D02*
Y819000D01*
G01X358700Y841386D02*
Y818590D01*
G01X358627Y849287D02*
X360000Y841500D01*
G01X357396Y848777D02*
X358700Y841386D01*
G01X348923Y863146D02*
X358627Y849287D01*
G01X347692Y862636D02*
X357396Y848777D01*
G01X344989Y847087D02*
X334683Y861806D01*
G01X346220Y847597D02*
X335914Y862316D01*
G01X346171Y840386D02*
X344989Y847087D01*
G01X347471Y840500D02*
X346220Y847597D01*
G01X346171Y819570D02*
Y840386D01*
G01X347471Y819980D02*
Y840500D01*
G01X335000Y823000D02*
X337686Y819163D01*
G01X335000Y837000D02*
Y823000D01*
G01X333912Y843174D02*
X335000Y837000D01*
G01Y823000D02*
X337686Y819163D01*
G01X335000Y837000D02*
Y823000D01*
G01X333912Y843174D02*
X335000Y837000D01*
G01X361000Y861000D02*
X372012Y845273D01*
G01X360098Y866114D02*
X361000Y861000D01*
G01X359769Y860490D02*
X358798Y865997D01*
G01X360098Y872882D02*
Y866114D01*
G01X358798Y865997D02*
Y872882D01*
G01Y865997D02*
Y872882D01*
G01X360098D02*
Y866114D01*
G01X359769Y860490D02*
X358798Y865997D01*
G01X360098Y866114D02*
X361000Y861000D01*
G01D02*
X372012Y845273D01*
G01X346200Y871101D02*
X347692Y862636D01*
G01X347500Y871218D02*
X348923Y863146D01*
G01X346200Y872882D02*
Y871101D01*
G01X347500Y872882D02*
Y871218D01*
G01X334901Y868062D02*
Y872882D01*
G01X335914Y862316D02*
X334901Y868062D01*
G01X347500Y871218D02*
X348923Y863146D01*
G01X346200Y871101D02*
X347692Y862636D01*
G01X347500Y872882D02*
Y871218D01*
G01X346200Y872882D02*
Y871101D01*
G01X334901Y868062D02*
Y872882D01*
G01X335914Y862316D02*
X334901Y868062D01*
G01X388287Y699150D02*
X462976Y592484D01*
G01X437104Y627166D02*
X387353Y698215D01*
G01X437104Y627166D02*
X387353Y698215D01*
G01X388287Y699150D02*
X462976Y592484D01*
G01X380422Y704656D02*
X388287Y699150D01*
G01X387353Y698215D02*
X379488Y703722D01*
G01X369925Y719646D02*
X380422Y704656D01*
G01X379488Y703722D02*
X368625Y719236D01*
G01X379488Y703722D02*
X368625Y719236D01*
G01X369925Y719646D02*
X380422Y704656D01*
G01X387353Y698215D02*
X379488Y703722D01*
G01X380422Y704656D02*
X388287Y699150D01*
G01X639215Y547461D02*
X395566Y718066D01*
G01X404126Y698403D02*
X375000Y740000D01*
G01X403192Y697469D02*
X374066Y739066D01*
G01X639215Y547461D02*
X395566Y718066D01*
G01X383814Y713550D02*
X490412Y561311D01*
G01X382583Y713040D02*
X489478Y560377D01*
G01X382500Y721000D02*
X383814Y713550D01*
G01X381269Y720490D02*
X382583Y713040D01*
G01X403192Y697469D02*
X374066Y739066D01*
G01X404126Y698403D02*
X375000Y740000D01*
G01X382583Y713040D02*
X489478Y560377D01*
G01X383814Y713550D02*
X490412Y561311D01*
G01X381269Y720490D02*
X382583Y713040D01*
G01X382500Y721000D02*
X383814Y713550D01*
G01X369925Y720600D02*
Y719646D01*
G01X368625Y719236D02*
Y720706D01*
G01X369924Y720704D02*
Y720600D01*
G01X368625Y719236D02*
Y720706D01*
G01Y719236D02*
Y720706D01*
G01X369925Y720600D02*
Y719646D01*
G01X369924Y720704D02*
Y720600D01*
G01X395922Y748563D02*
X665110Y560075D01*
G01X396856Y749497D02*
X666044Y561009D01*
G01X381566Y769066D02*
X395922Y748563D01*
G01X396856Y749497D02*
X666044Y561009D01*
G01X395922Y748563D02*
X665110Y560075D01*
G01X381566Y769066D02*
X395922Y748563D01*
G01X392659Y739336D02*
X384166Y751466D01*
G01X385100Y752400D02*
X393593Y740270D01*
G01X650693Y558661D02*
X392659Y739336D01*
G01X393593Y740270D02*
X651627Y559595D01*
G01X392657Y746054D02*
X385794Y755855D01*
G01X393591Y746987D02*
X386728Y756789D01*
G01X661829Y557577D02*
X392658Y746053D01*
G01X662763Y558511D02*
X393591Y746987D01*
G01X393593Y740270D02*
X651627Y559595D01*
G01X650693Y558661D02*
X392659Y739336D01*
G01X385100Y752400D02*
X393593Y740270D01*
G01X392659Y739336D02*
X384166Y751466D01*
G01X393591Y746987D02*
X386728Y756789D01*
G01X392657Y746054D02*
X385794Y755855D01*
G01X662763Y558511D02*
X393591Y746987D01*
G01X661829Y557577D02*
X392658Y746053D01*
G01X400438Y722596D02*
X382300Y748500D01*
G01X399504Y721662D02*
X381366Y747566D01*
G01X654916Y544408D02*
X400438Y722596D01*
G01X653982Y543474D02*
X399504Y721662D01*
G01D02*
X381366Y747566D01*
G01X400438Y722596D02*
X382300Y748500D01*
G01X653982Y543474D02*
X399504Y721662D01*
G01X654916Y544408D02*
X400438Y722596D01*
G01X395566Y718066D02*
X377593Y743735D01*
G01X396500Y719000D02*
X378527Y744669D01*
G01X640149Y548395D02*
X396500Y719000D01*
G01D02*
X378527Y744669D01*
G01X395566Y718066D02*
X377593Y743735D01*
G01X640149Y548395D02*
X396500Y719000D01*
G01X372867Y734757D02*
X382500Y721000D01*
G01X371933Y733823D02*
X381269Y720490D01*
G01X371933Y733823D02*
X381269Y720490D01*
G01X372867Y734757D02*
X382500Y721000D01*
G01X398045Y786524D02*
X403802Y778302D01*
G01X401447Y774793D02*
X395000Y784000D01*
G01X400513Y773859D02*
X394066Y783066D01*
G01X678546Y579174D02*
X400513Y773859D01*
G01X398045Y786524D02*
X403802Y778302D01*
G01X400513Y773859D02*
X394066Y783066D01*
G01X401447Y774793D02*
X395000Y784000D01*
G01X678546Y579174D02*
X400513Y773859D01*
G01X399049Y768879D02*
X679132Y572643D01*
G01X399983Y769812D02*
X680066Y573576D01*
G01X391169Y780134D02*
X399049Y768879D01*
G01X392103Y781068D02*
X399983Y769812D01*
G01D02*
X680066Y573576D01*
G01X399049Y768879D02*
X679132Y572643D01*
G01X392103Y781068D02*
X399983Y769812D01*
G01X391169Y780134D02*
X399049Y768879D01*
G01X395869Y765849D02*
X672787Y571957D01*
G01X396804Y766783D02*
X673721Y572891D01*
G01X389066Y775566D02*
X395869Y765849D01*
G01X390000Y776500D02*
X396804Y766783D01*
G01D02*
X673721Y572891D01*
G01X395869Y765849D02*
X672787Y571957D01*
G01X390000Y776500D02*
X396804Y766783D01*
G01X389066Y775566D02*
X395869Y765849D01*
G01X394059Y760863D02*
X669840Y567759D01*
G01X394996Y761794D02*
X670774Y568693D01*
G01X385539Y773033D02*
X394059Y760863D01*
G01X386473Y773967D02*
X394996Y761794D01*
G01D02*
X670774Y568693D01*
G01X394059Y760863D02*
X669840Y567759D01*
G01X386473Y773967D02*
X394996Y761794D01*
G01X385539Y773033D02*
X394059Y760863D01*
G01X382500Y770000D02*
X396856Y749497D01*
G01X382500Y770000D02*
X396856Y749497D01*
G01X397989Y800818D02*
X409586Y784252D01*
G01X410520Y785186D02*
X398923Y801752D01*
G01X389066Y807066D02*
X397989Y800818D01*
G01X398923Y801752D02*
X390000Y808000D01*
G01X379254Y821079D02*
X389066Y807066D01*
G01X390000Y808000D02*
X380485Y821589D01*
G01X393290Y821527D02*
X416595Y788245D01*
G01X394590Y821937D02*
X417529Y789179D01*
G01X390000Y808000D02*
X380485Y821589D01*
G01X379254Y821079D02*
X389066Y807066D01*
G01X398923Y801752D02*
X390000Y808000D01*
G01X389066Y807066D02*
X397989Y800818D01*
G01X410520Y785186D02*
X398923Y801752D01*
G01X397989Y800818D02*
X409586Y784252D01*
G01X394590Y821937D02*
X417529Y789179D01*
G01X393290Y821527D02*
X416595Y788245D01*
G01X401170Y789649D02*
X406212Y782448D01*
G01X405278Y781514D02*
X400236Y788715D01*
G01X390932Y796818D02*
X401170Y789649D01*
G01X400236Y788715D02*
X389998Y795884D01*
G01X377064Y816625D02*
X390932Y796818D01*
G01X389998Y795884D02*
X375833Y816115D01*
G01D02*
X370781Y844763D01*
G01X375833Y816115D02*
X370781Y844763D01*
G01X389998Y795884D02*
X375833Y816115D01*
G01X377064Y816625D02*
X390932Y796818D01*
G01X400236Y788715D02*
X389998Y795884D01*
G01X390932Y796818D02*
X401170Y789649D01*
G01X405278Y781514D02*
X400236Y788715D01*
G01X401170Y789649D02*
X406212Y782448D01*
G01X398979Y787458D02*
X404736Y779236D01*
G01X398979Y787458D02*
X404736Y779236D01*
G01X376142Y838729D02*
X379254Y821079D01*
G01X380485Y821589D02*
X377463Y838729D01*
G01X381167Y867232D02*
X376142Y838729D01*
G01X377463D02*
X382488Y867232D01*
G01X393290Y840886D02*
Y821527D01*
G01X394590Y841000D02*
Y821937D01*
G01X391863Y848973D02*
X393290Y840886D01*
G01X393184Y848973D02*
X394590Y841000D01*
G01X394625Y864637D02*
X391863Y848973D01*
G01X395946Y864637D02*
X393184Y848973D01*
G01X377463Y838729D02*
X382488Y867232D01*
G01X381167D02*
X376142Y838729D01*
G01X380485Y821589D02*
X377463Y838729D01*
G01X376142D02*
X379254Y821079D01*
G01X394590Y841000D02*
Y821937D01*
G01X393290Y840886D02*
Y821527D01*
G01X393184Y848973D02*
X394590Y841000D01*
G01X391863Y848973D02*
X393290Y840886D01*
G01X395946Y864637D02*
X393184Y848973D01*
G01X394625Y864637D02*
X391863Y848973D01*
G01X372012Y845273D02*
X377064Y816625D01*
G01X372012Y845273D02*
X377064Y816625D01*
G01X380846Y869054D02*
X381167Y867232D01*
G01X382488D02*
X382146Y869172D01*
G01X380846Y872882D02*
Y869054D01*
G01X382146Y869172D02*
Y872882D01*
G01X393444Y871335D02*
X394625Y864637D01*
G01X394744Y871451D02*
X395946Y864637D01*
G01X393444Y872882D02*
Y871335D01*
G01X394744Y872882D02*
Y871451D01*
G01X382146Y869172D02*
Y872882D01*
G01X380846D02*
Y869054D01*
G01X382488Y867232D02*
X382146Y869172D01*
G01X380846Y869054D02*
X381167Y867232D01*
G01X394744Y871451D02*
X395946Y864637D01*
G01X393444Y871335D02*
X394625Y864637D01*
G01X394744Y872882D02*
Y871451D01*
G01X393444Y872882D02*
Y871335D01*
G01X466163Y133783D02*
X419816Y143642D01*
G01X466163Y133783D02*
X419816Y143642D01*
G01X431800Y158600D02*
X464456D01*
G01X463917Y157300D02*
X431261D01*
G01X414700Y175700D02*
X431800Y158600D01*
G01X431261Y157300D02*
X413400Y175161D01*
G01D02*
Y315700D01*
G01Y175161D02*
Y315700D01*
G01Y175161D02*
Y315700D01*
G01Y175161D02*
Y315700D01*
G01Y175161D02*
Y315700D01*
G01X431261Y157300D02*
X413400Y175161D01*
G01X414700Y175700D02*
X431800Y158600D01*
G01X463917Y157300D02*
X431261D01*
G01X431800Y158600D02*
X464456D01*
G01X419953Y144942D02*
X466122Y135121D01*
G01X404700Y144942D02*
X419953D01*
G01X419816Y143642D02*
X404700D01*
G01X419816D02*
X404700D01*
G01Y144942D02*
X419953D01*
G01D02*
X466122Y135121D01*
G01X414988Y154315D02*
X402400D01*
G01Y155615D02*
X415125D01*
G01X471821Y142233D02*
X414988Y154315D01*
G01X415125Y155615D02*
X471783Y143571D01*
G01X415125Y155615D02*
X471783Y143571D01*
G01X471821Y142233D02*
X414988Y154315D01*
G01X402400Y155615D02*
X415125D01*
G01X414988Y154315D02*
X402400D01*
G01X431800Y158600D02*
X464456D01*
G01X463917Y157300D02*
X431261D01*
G01X414700Y175700D02*
X431800Y158600D01*
G01X431261Y157300D02*
X413400Y175161D01*
G01D02*
Y315700D01*
G01Y175161D02*
Y315700D01*
G01Y175161D02*
Y315700D01*
G01Y175161D02*
Y315700D01*
G01Y175161D02*
Y315700D01*
G01X431261Y157300D02*
X413400Y175161D01*
G01X414700Y175700D02*
X431800Y158600D01*
G01X463917Y157300D02*
X431261D01*
G01X431800Y158600D02*
X464456D01*
G01X414700Y295481D02*
Y175700D01*
G01Y295481D02*
Y175700D01*
G01Y295481D02*
Y175700D01*
G01Y295481D02*
Y175700D01*
G01Y300181D02*
Y298531D01*
G01Y304881D02*
Y303231D01*
G01Y316239D02*
Y307931D01*
G01Y300181D02*
Y298531D01*
G01Y304881D02*
Y303231D01*
G01Y316239D02*
Y307931D01*
G01Y300181D02*
Y298531D01*
G01Y304881D02*
Y303231D01*
G01Y316239D02*
Y307931D01*
G01Y300181D02*
Y298531D01*
G01Y304881D02*
Y303231D01*
G01Y316239D02*
Y307931D01*
G01X409389Y321550D02*
X414700Y316239D01*
G01X413400Y315700D02*
X408850Y320250D01*
G01X405790Y321550D02*
X409389D01*
G01X408850Y320250D02*
X405372D01*
G01X408850D02*
X405372D01*
G01X405790Y321550D02*
X409389D01*
G01X413400Y315700D02*
X408850Y320250D01*
G01X409389Y321550D02*
X414700Y316239D01*
G01X409389Y321550D02*
X414700Y316239D01*
G01X413400Y315700D02*
X408850Y320250D01*
G01X405790Y321550D02*
X409389D01*
G01X408850Y320250D02*
X405372D01*
G01X408850D02*
X405372D01*
G01X405790Y321550D02*
X409389D01*
G01X413400Y315700D02*
X408850Y320250D01*
G01X409389Y321550D02*
X414700Y316239D01*
G01X644683Y529963D02*
X404126Y698403D01*
G01X643749Y529029D02*
X403192Y697469D01*
G01X643749Y529029D02*
X403192Y697469D01*
G01X644683Y529963D02*
X404126Y698403D01*
G01X409586Y784252D02*
X694087Y585043D01*
G01X695021Y585977D02*
X410520Y785186D01*
G01X416595Y788245D02*
X692144Y595304D01*
G01X417529Y789179D02*
X693078Y596238D01*
G01X695021Y585977D02*
X410520Y785186D01*
G01X409586Y784252D02*
X694087Y585043D01*
G01X417529Y789179D02*
X693078Y596238D01*
G01X416595Y788245D02*
X692144Y595304D01*
G01X406212Y782448D02*
X688209Y584991D01*
G01X687275Y584057D02*
X405278Y781514D01*
G01X687275Y584057D02*
X405278Y781514D01*
G01X406212Y782448D02*
X688209Y584991D01*
G01X403802Y778302D02*
X678865Y585698D01*
G01X404736Y779236D02*
X679799Y586632D01*
G01X679480Y580108D02*
X401447Y774793D01*
G01X404736Y779236D02*
X679799Y586632D01*
G01X403802Y778302D02*
X678865Y585698D01*
G01X679480Y580108D02*
X401447Y774793D01*
G01X428379Y787841D02*
X695411Y600868D01*
G01X429313Y788775D02*
X696345Y601802D01*
G01X407269Y817990D02*
X428379Y787841D01*
G01X408500Y818500D02*
X429313Y788775D01*
G01X429427Y799553D02*
X437444Y788101D01*
G01X422605Y811564D02*
X438378Y789035D01*
G01X421374Y811054D02*
X429427Y799553D01*
G01X422605Y811564D02*
X438378Y789035D01*
G01X418700Y826221D02*
X421374Y811054D01*
G01X420000Y826335D02*
X422605Y811564D01*
G01X429313Y788775D02*
X696345Y601802D01*
G01X428379Y787841D02*
X695411Y600868D01*
G01X408500Y818500D02*
X429313Y788775D01*
G01X407269Y817990D02*
X428379Y787841D01*
G01X422605Y811564D02*
X438378Y789035D01*
G01X429427Y799553D02*
X437444Y788101D01*
G01X421374Y811054D02*
X429427Y799553D01*
G01X420000Y826335D02*
X422605Y811564D01*
G01X418700Y826221D02*
X421374Y811054D01*
G01X406204Y824034D02*
X407269Y817990D01*
G01X407504Y824148D02*
X408500Y818500D01*
G01X406204Y841386D02*
Y824034D01*
G01X407504Y841500D02*
Y824148D01*
G01X404674Y850057D02*
X406204Y841386D01*
G01X405995Y850057D02*
X407504Y841500D01*
G01X407141Y864045D02*
X404674Y850057D01*
G01X408462Y864045D02*
X405995Y850057D01*
G01X418700Y840886D02*
Y826221D01*
G01X420000Y841000D02*
Y826335D01*
G01X417886Y845496D02*
X418700Y840886D01*
G01X418335Y850441D02*
X420000Y841000D01*
G01X417014Y850441D02*
X417886Y845496D01*
G01X418335Y850441D02*
X420000Y841000D01*
G01X407504Y824148D02*
X408500Y818500D01*
G01X406204Y824034D02*
X407269Y817990D01*
G01X407504Y841500D02*
Y824148D01*
G01X406204Y841386D02*
Y824034D01*
G01X405995Y850057D02*
X407504Y841500D01*
G01X404674Y850057D02*
X406204Y841386D01*
G01X408462Y864045D02*
X405995Y850057D01*
G01X407141Y864045D02*
X404674Y850057D01*
G01X420000Y841000D02*
Y826335D01*
G01X418700Y840886D02*
Y826221D01*
G01X418335Y850441D02*
X420000Y841000D01*
G01X417886Y845496D02*
X418700Y840886D01*
G01X417014Y850441D02*
X417886Y845496D01*
G01X406042Y870279D02*
X407141Y864045D01*
G01X407342Y870396D02*
X408462Y864045D01*
G01X406042Y872882D02*
Y870279D01*
G01X407342Y872882D02*
Y870396D01*
G01X419571Y864943D02*
X417014Y850441D01*
G01X420892Y864943D02*
X418335Y850441D01*
G01X418641Y870217D02*
X419571Y864943D01*
G01X419941Y870334D02*
X420892Y864943D01*
G01X418641Y872882D02*
Y870217D01*
G01X419941Y872882D02*
Y870334D01*
G01X407342Y870396D02*
X408462Y864045D01*
G01X406042Y870279D02*
X407141Y864045D01*
G01X407342Y872882D02*
Y870396D01*
G01X406042Y872882D02*
Y870279D01*
G01X420892Y864943D02*
X418335Y850441D01*
G01X419571Y864943D02*
X417014Y850441D01*
G01X419941Y870334D02*
X420892Y864943D01*
G01X418641Y870217D02*
X419571Y864943D01*
G01X419941Y872882D02*
Y870334D01*
G01X418641Y872882D02*
Y870217D01*
G01X466122Y135121D02*
X516445Y149096D01*
G01X516486Y147758D02*
X466163Y133783D01*
G01X516486Y147758D02*
X466163Y133783D01*
G01X466122Y135121D02*
X516445Y149096D01*
G01X482704Y152804D02*
X468413D01*
G01X464456Y158600D02*
X468952Y154104D01*
G01X468413Y152804D02*
X463917Y157300D01*
G01X468413Y152804D02*
X463917Y157300D01*
G01X464456Y158600D02*
X468952Y154104D01*
G01X482704Y152804D02*
X468413D01*
G01X482704D02*
X468413D01*
G01X464456Y158600D02*
X468952Y154104D01*
G01X468413Y152804D02*
X463917Y157300D01*
G01X468413Y152804D02*
X463917Y157300D01*
G01X464456Y158600D02*
X468952Y154104D01*
G01X482704Y152804D02*
X468413D01*
G01X459610Y424600D02*
X478984Y420482D01*
G01X459355Y423325D02*
X478984Y419152D01*
G01X459339Y423328D02*
X459355Y423325D01*
G01X459346Y424650D02*
X459610Y424600D01*
G01X459355Y423325D02*
X478984Y419152D01*
G01X459339Y423328D02*
X459355Y423325D01*
G01D02*
X478984Y419152D01*
G01X459610Y424600D02*
X478984Y420482D01*
G01X459346Y424650D02*
X459610Y424600D01*
G01X459339Y423328D02*
X459355Y423325D01*
G01X459610Y424600D02*
X478984Y420482D01*
G01X459346Y424650D02*
X459610Y424600D01*
G01X462227Y433847D02*
X477569Y430585D01*
G01Y429255D02*
X462204Y432522D01*
G01X477569Y429255D02*
X462204Y432522D01*
G01X462227Y433847D02*
X477569Y430585D01*
G01X462530Y427844D02*
X479480Y424240D01*
G01Y425570D02*
X462553Y429169D01*
G01X479480Y425570D02*
X462553Y429169D01*
G01X462530Y427844D02*
X479480Y424240D01*
G01X486851Y556118D02*
X437104Y627166D01*
G01X462976Y592483D02*
X475380Y574768D01*
G01X486851Y556118D02*
X437104Y627166D01*
G01X486851Y556118D02*
X437104Y627166D01*
G01X462976Y592483D02*
X475380Y574768D01*
G01X437444Y788101D02*
X702239Y602688D01*
G01X438378Y789035D02*
X703173Y603622D01*
G01X438378Y789035D02*
X703173Y603622D01*
G01X437444Y788101D02*
X702239Y602688D01*
G01X489086Y161025D02*
X506762D01*
G01X507301Y159725D02*
X489625D01*
G01X482165Y154104D02*
X489086Y161025D01*
G01X489625Y159725D02*
X482704Y152804D01*
G01X468952Y154104D02*
X482165D01*
G01X468952D02*
X482165D01*
G01X489625Y159725D02*
X482704Y152804D01*
G01X482165Y154104D02*
X489086Y161025D01*
G01X507301Y159725D02*
X489625D01*
G01X489086Y161025D02*
X506762D01*
G01X519755Y155323D02*
X471821Y142233D01*
G01X471783Y143571D02*
X519717Y156661D01*
G01X471783Y143571D02*
X519717Y156661D01*
G01X519755Y155323D02*
X471821Y142233D01*
G01X489086Y161025D02*
X506762D01*
G01X507301Y159725D02*
X489625D01*
G01X482165Y154104D02*
X489086Y161025D01*
G01X489625Y159725D02*
X482704Y152804D01*
G01X468952Y154104D02*
X482165D01*
G01X468952D02*
X482165D01*
G01X489625Y159725D02*
X482704Y152804D01*
G01X482165Y154104D02*
X489086Y161025D01*
G01X507301Y159725D02*
X489625D01*
G01X489086Y161025D02*
X506762D01*
G01X500894Y425140D02*
X528322Y419308D01*
G01X500894Y423810D02*
X527816Y418086D01*
G01X478984Y420482D02*
X500894Y425140D01*
G01X478984Y419152D02*
X500894Y423810D01*
G01D02*
X527816Y418086D01*
G01X500894Y425140D02*
X528322Y419308D01*
G01X478984Y419152D02*
X500894Y423810D01*
G01X478984Y420482D02*
X500894Y425140D01*
G01X497869Y434900D02*
X535257Y426953D01*
G01X534751Y425731D02*
X497869Y433570D01*
G01X477569Y430585D02*
X497869Y434900D01*
G01Y433570D02*
X477569Y429255D01*
G01X497869Y433570D02*
X477569Y429255D01*
G01Y430585D02*
X497869Y434900D01*
G01X534751Y425731D02*
X497869Y433570D01*
G01Y434900D02*
X535257Y426953D01*
G01X501169Y428850D02*
X528754Y422987D01*
G01X529260Y424209D02*
X501169Y430180D01*
G01X479480Y424240D02*
X501169Y428850D01*
G01Y430180D02*
X479480Y425570D01*
G01X501169Y430180D02*
X479480Y425570D01*
G01Y424240D02*
X501169Y428850D01*
G01X529260Y424209D02*
X501169Y430180D01*
G01Y428850D02*
X528754Y422987D01*
G01X682713Y418975D02*
X486851Y556118D01*
G01X682713Y418975D02*
X486851Y556118D01*
G01X682713Y418975D02*
X486851Y556118D01*
G01X487785Y557052D02*
X513337Y539160D01*
G01X475380Y574768D02*
X487785Y557052D01*
G01X475380Y574768D02*
X487785Y557052D01*
G01D02*
X513337Y539160D01*
G01X489478Y560377D02*
X683727Y424362D01*
G01X489478Y560377D02*
X683727Y424362D01*
G01X489478Y560377D02*
X683727Y424362D01*
G01X489478Y560377D02*
X683727Y424362D01*
G01X489478Y560377D02*
X683727Y424362D01*
G01X489478Y560377D02*
X683727Y424362D01*
G01X490412Y561311D02*
X582521Y496815D01*
G01X489478Y560377D02*
X683727Y424362D01*
G01X489478Y560377D02*
X683727Y424362D01*
G01X490412Y561311D02*
X582521Y496815D01*
G01X538458Y70058D02*
X535950Y67550D01*
G01X535814Y74085D02*
X537538Y72361D01*
G01X530469Y75032D02*
X535814Y74085D01*
G01X525901Y74227D02*
X530469Y75032D01*
G01X521665Y77193D02*
X525901Y74227D01*
G01X525700Y58962D02*
X541600D01*
G01X525700Y60262D02*
X541600D01*
G01X522504Y57866D02*
G02X525700Y58962I3196J-4112D01*
G01X521706Y58894D02*
G02X525700Y60262I3992J-5141D01*
G01X521673Y57057D02*
G02X522504Y57866I4026J-3305D01*
G01X521706Y58894D02*
G02X525700Y60262I3992J-5141D01*
G01X521100Y55464D02*
G02X521673Y57057I2500J0D01*
G01X520670Y57885D02*
G02X520913Y58152I2929J-2421D01*
G01X519800Y55465D02*
G02X520670Y57885I3800J0D01*
G01X521100Y52400D02*
Y55464D01*
G01X519800Y52400D02*
Y55465D01*
G01X522300Y49300D02*
G02X521100Y52400I3404J3100D01*
G01X519952Y51065D02*
G02X519800Y52400I5753J1331D01*
G01X521630Y48131D02*
G02X519952Y51065I4039J4257D01*
G01X524150Y47450D02*
X522300Y49300D01*
G01X523230Y46531D02*
X521630Y48131D01*
G01X525667Y46550D02*
G02X524150Y47450I1034J3471D01*
G01X525296Y45304D02*
G02X523230Y46531I1399J4709D01*
G01X526700Y46400D02*
G02X525667Y46550I-1J3622D01*
G01X525296Y45304D02*
G02X523230Y46531I1399J4709D01*
G01X526700Y45100D02*
G02X525296Y45304I-2J4922D01*
G01X527600Y46400D02*
X526700D01*
G01X527600Y45100D02*
X526700D01*
G01X529078Y47021D02*
G02X527600Y46400I-1478J1448D01*
G01X528661Y45270D02*
G02X527600Y45100I-1057J3200D01*
G01X530048Y46151D02*
G02X528661Y45270I-2442J2311D01*
G01X532178Y50121D02*
X529078Y47021D01*
G01X532871Y48974D02*
X530048Y46151D01*
G01X532758Y50475D02*
X532178Y50121D01*
G01X533210Y49227D02*
X533129Y49178D01*
G01X538458Y70058D02*
X535950Y67550D01*
G01X535814Y74085D02*
X537538Y72361D01*
G01X530469Y75032D02*
X535814Y74085D01*
G01X525901Y74227D02*
X530469Y75032D01*
G01X521665Y77193D02*
X525901Y74227D01*
G01X525700Y60262D02*
X541600D01*
G01X525700Y58962D02*
X541600D01*
G01X521706Y58894D02*
G02X525700Y60262I3992J-5141D01*
G01X522504Y57866D02*
G02X525700Y58962I3196J-4112D01*
G01X521673Y57057D02*
G02X522504Y57866I4026J-3305D01*
G01X520670Y57885D02*
G02X520913Y58152I2929J-2421D01*
G01X521100Y55464D02*
G02X521673Y57057I2500J0D01*
G01X519800Y55465D02*
G02X520670Y57885I3800J0D01*
G01X521100Y55464D02*
G02X521673Y57057I2500J0D01*
G01X519800Y52400D02*
Y55465D01*
G01X521100Y52400D02*
Y55464D01*
G01X519952Y51065D02*
G02X519800Y52400I5753J1331D01*
G01X522300Y49300D02*
G02X521100Y52400I3404J3100D01*
G01X521630Y48131D02*
G02X519952Y51065I4039J4257D01*
G01X522300Y49300D02*
G02X521100Y52400I3404J3100D01*
G01X523230Y46531D02*
X521630Y48131D01*
G01X524150Y47450D02*
X522300Y49300D01*
G01X525296Y45304D02*
G02X523230Y46531I1399J4709D01*
G01X525667Y46550D02*
G02X524150Y47450I1034J3471D01*
G01X526700Y46400D02*
G02X525667Y46550I-1J3622D01*
G01X526700Y45100D02*
G02X525296Y45304I-2J4922D01*
G01X526700Y46400D02*
G02X525667Y46550I-1J3622D01*
G01X527600Y45100D02*
X526700D01*
G01X527600Y46400D02*
X526700D01*
G01X528661Y45270D02*
G02X527600Y45100I-1057J3200D01*
G01X529078Y47021D02*
G02X527600Y46400I-1478J1448D01*
G01X530048Y46151D02*
G02X528661Y45270I-2442J2311D01*
G01X529078Y47021D02*
G02X527600Y46400I-1478J1448D01*
G01X532871Y48974D02*
X530048Y46151D01*
G01X532178Y50121D02*
X529078Y47021D01*
G01X533210Y49227D02*
X533129Y49178D01*
G01X532758Y50475D02*
X532178Y50121D01*
G01X530469Y76353D02*
X536439Y75300D01*
G01X526206Y75601D02*
X530469Y76353D01*
G01X522599Y78127D02*
X526206Y75601D01*
G01X519003Y80995D02*
X521665Y77193D01*
G01X520234Y81505D02*
X522599Y78127D01*
G01X518300Y84986D02*
X519003Y80995D01*
G01X519600Y85100D02*
X520234Y81505D01*
G01X518300Y87314D02*
Y84986D01*
G01X519600Y87200D02*
Y85100D01*
G01X519945Y96651D02*
X518300Y87314D01*
G01X521266Y96651D02*
X519600Y87200D01*
G01X518945Y102322D02*
X519945Y96651D01*
G01X520270Y102299D02*
X521266Y96651D01*
G01X519315Y104060D02*
X518945Y102322D01*
G01X520537Y103554D02*
X520270Y102299D01*
G01X521172Y106921D02*
X519315Y104060D01*
G01X522112Y105981D02*
X520537Y103554D01*
G01X532245Y114104D02*
X521172Y106921D01*
G01X532751Y112882D02*
X522112Y105981D01*
G01X530469Y76353D02*
X536439Y75300D01*
G01X526206Y75601D02*
X530469Y76353D01*
G01X522599Y78127D02*
X526206Y75601D01*
G01X520234Y81505D02*
X522599Y78127D01*
G01X519003Y80995D02*
X521665Y77193D01*
G01X519600Y85100D02*
X520234Y81505D01*
G01X518300Y84986D02*
X519003Y80995D01*
G01X519600Y87200D02*
Y85100D01*
G01X518300Y87314D02*
Y84986D01*
G01X521266Y96651D02*
X519600Y87200D01*
G01X519945Y96651D02*
X518300Y87314D01*
G01X520270Y102299D02*
X521266Y96651D01*
G01X518945Y102322D02*
X519945Y96651D01*
G01X520537Y103554D02*
X520270Y102299D01*
G01X519315Y104060D02*
X518945Y102322D01*
G01X522112Y105981D02*
X520537Y103554D01*
G01X521172Y106921D02*
X519315Y104060D01*
G01X532751Y112882D02*
X522112Y105981D01*
G01X532245Y114104D02*
X521172Y106921D01*
G01X534098Y114498D02*
X532245Y114104D01*
G01X534604Y113276D02*
X532751Y112882D01*
G01X550369Y125062D02*
X534098Y114498D01*
G01X551309Y124122D02*
X534604Y113276D01*
G01D02*
X532751Y112882D01*
G01X534098Y114498D02*
X532245Y114104D01*
G01X551309Y124122D02*
X534604Y113276D01*
G01X550369Y125062D02*
X534098Y114498D01*
G01X512337Y166600D02*
X517200D01*
G01X517286Y165300D02*
X512876D01*
G01X506762Y161025D02*
X512337Y166600D01*
G01X512876Y165300D02*
X507301Y159725D01*
G01X512876Y165300D02*
X507301Y159725D01*
G01X506762Y161025D02*
X512337Y166600D01*
G01X517286Y165300D02*
X512876D01*
G01X512337Y166600D02*
X517200D01*
G01X527123Y146827D02*
X549169D01*
G01X549555Y145527D02*
X526986D01*
G01X516445Y149096D02*
X527123Y146827D01*
G01X526986Y145527D02*
X516486Y147758D01*
G01X526986Y145527D02*
X516486Y147758D01*
G01X516445Y149096D02*
X527123Y146827D01*
G01X549555Y145527D02*
X526986D01*
G01X527123Y146827D02*
X549169D01*
G01X528338Y153498D02*
X519755Y155323D01*
G01X519717Y156661D02*
X528338Y154828D01*
G01X559042Y160023D02*
X528338Y153498D01*
G01Y154828D02*
X558536Y161245D01*
G01X528338Y154828D02*
X558536Y161245D01*
G01X559042Y160023D02*
X528338Y153498D01*
G01X519717Y156661D02*
X528338Y154828D01*
G01Y153498D02*
X519755Y155323D01*
G01X512337Y166600D02*
X517200D01*
G01X517286Y165300D02*
X512876D01*
G01X506762Y161025D02*
X512337Y166600D01*
G01X512876Y165300D02*
X507301Y159725D01*
G01X512876Y165300D02*
X507301Y159725D01*
G01X506762Y161025D02*
X512337Y166600D01*
G01X517286Y165300D02*
X512876D01*
G01X512337Y166600D02*
X517200D01*
G01X528322Y419308D02*
X557369Y400444D01*
G01X527816Y418086D02*
X556882Y399209D01*
G01X527816Y418086D02*
X556882Y399209D01*
G01X528322Y419308D02*
X557369Y400444D01*
G01X535257Y426953D02*
X562424Y409315D01*
G01X561938Y408080D02*
X534751Y425731D01*
G01X561938Y408080D02*
X534751Y425731D01*
G01X535257Y426953D02*
X562424Y409315D01*
G01X528754Y422987D02*
X558450Y403702D01*
G01X533857Y421224D02*
X529260Y424209D01*
G01X533857Y421224D02*
X529260Y424209D01*
G01X528754Y422987D02*
X558450Y403702D01*
G01X528754Y422987D02*
X558450Y403702D01*
G01X528754Y422987D02*
X558450Y403702D01*
G01X528754Y422987D02*
X558450Y403702D01*
G01X528754Y422987D02*
X558450Y403702D01*
G01X513337Y539160D02*
X683647Y419909D01*
G01X513337Y539160D02*
X683647Y419909D01*
G01X568017Y59399D02*
X586986Y59301D01*
G01X568020Y60700D02*
X586990Y60601D01*
G01X564400Y57900D02*
G02X568017Y59399I3620J-3622D01*
G01X563480Y58820D02*
G02X568020Y60700I4540J-4542D01*
G01X563000Y54520D02*
G02X564400Y57900I4780J0D01*
G01X561700Y54519D02*
G02X563480Y58820I6081J2D01*
G01X563000Y52300D02*
Y54520D01*
G01X561700Y52299D02*
Y54519D01*
G01X564882Y47758D02*
G02X563000Y52300I4542J4543D01*
G01X562143Y49720D02*
G02X561700Y52299I7281J2578D01*
G01X563960Y46840D02*
G02X562143Y49720I5456J5455D01*
G01X566276Y46362D02*
X564882Y47758D01*
G01X565363Y45437D02*
X563960Y46840D01*
G01X568600Y45400D02*
G02X566276Y46362I-1J3286D01*
G01X567227Y44309D02*
G02X565363Y45437I1362J4354D01*
G01X568600Y44100D02*
G02X567227Y44309I-4J4587D01*
G01X569400Y45400D02*
X568600D01*
G01X569401Y44100D02*
X568600D01*
G01X570433Y45638D02*
G02X569400Y45400I-1033J2123D01*
G01X571002Y44469D02*
G02X569401Y44100I-1602J3292D01*
G01X571002Y44469D02*
G02X569401Y44100I-1602J3292D01*
G01X541259Y51684D02*
G03X541868Y54843I-6703J2930D01*
G01X542451Y51163D02*
G03X542543Y51381I-7892J3459D01*
G01X542217Y50673D02*
G03X542451Y51163I-7654J3956D01*
G01X540872Y50924D02*
G03X541259Y51684I-6315J3694D01*
G01X542451Y51163D02*
G03X542543Y51381I-7892J3459D01*
G01X542217Y50673D02*
G03X542451Y51163I-7654J3956D01*
G01X541995Y50268D02*
G03X542217Y50673I-7442J4343D01*
G01X541361Y47131D02*
G02X540766Y50692I2979J2328D01*
G01X542385Y47932D02*
G02X541995Y50268I1955J1527D01*
G01X544721Y42843D02*
X541361Y47130D01*
G01X545755Y43632D02*
X542385Y47932D01*
G01X550115Y44461D02*
G02X544726Y42837I-3004J216D01*
G01X548818Y44554D02*
G02X545753Y43635I-1707J123D01*
G01X550160Y45085D02*
X550115Y44461D01*
G01X548877Y45377D02*
X548818Y44554D01*
G01X553527Y53638D02*
X550160Y45085D01*
G01X552373Y54258D02*
X548877Y45377D01*
G01X559395Y62019D02*
X553527Y53638D01*
G01X558164Y62529D02*
X552373Y54258D01*
G01X564611Y91602D02*
X559395Y62019D01*
G01X563290Y91602D02*
X558164Y62529D01*
G01X546430Y71169D02*
G02X543132Y69803I-3298J3298D01*
G01X547350Y70249D02*
G02X547286Y70186I-4216J4219D01*
G01X550380Y75119D02*
X546430Y71169D01*
G01X551590Y74489D02*
X547350Y70249D01*
G01X568020Y60700D02*
X586990Y60601D01*
G01X568017Y59399D02*
X586986Y59301D01*
G01X563480Y58820D02*
G02X568020Y60700I4540J-4542D01*
G01X564400Y57900D02*
G02X568017Y59399I3620J-3622D01*
G01X561700Y54519D02*
G02X563480Y58820I6081J2D01*
G01X563000Y54520D02*
G02X564400Y57900I4780J0D01*
G01X561700Y52299D02*
Y54519D01*
G01X563000Y52300D02*
Y54520D01*
G01X562143Y49720D02*
G02X561700Y52299I7281J2578D01*
G01X564882Y47758D02*
G02X563000Y52300I4542J4543D01*
G01X563960Y46840D02*
G02X562143Y49720I5456J5455D01*
G01X564882Y47758D02*
G02X563000Y52300I4542J4543D01*
G01X565363Y45437D02*
X563960Y46840D01*
G01X566276Y46362D02*
X564882Y47758D01*
G01X567227Y44309D02*
G02X565363Y45437I1362J4354D01*
G01X568600Y45400D02*
G02X566276Y46362I-1J3286D01*
G01X568600Y44100D02*
G02X567227Y44309I-4J4587D01*
G01X568600Y45400D02*
G02X566276Y46362I-1J3286D01*
G01X569401Y44100D02*
X568600D01*
G01X569400Y45400D02*
X568600D01*
G01X571002Y44469D02*
G02X569401Y44100I-1602J3292D01*
G01X570433Y45638D02*
G02X569400Y45400I-1033J2123D01*
G01X570433Y45638D02*
G02X569400Y45400I-1033J2123D01*
G01X542451Y51163D02*
G03X542543Y51381I-7892J3459D01*
G01X541259Y51684D02*
G03X541868Y54843I-6703J2930D01*
G01X540872Y50924D02*
G03X541259Y51684I-6315J3694D01*
G01X542217Y50673D02*
G03X542451Y51163I-7654J3956D01*
G01X541259Y51684D02*
G03X541868Y54843I-6703J2930D01*
G01X540872Y50924D02*
G03X541259Y51684I-6315J3694D01*
G01X541995Y50268D02*
G03X542217Y50673I-7442J4343D01*
G01X540872Y50924D02*
G03X541259Y51684I-6315J3694D01*
G01X542385Y47932D02*
G02X541995Y50268I1955J1527D01*
G01X541361Y47131D02*
G02X540766Y50692I2979J2328D01*
G01X545755Y43632D02*
X542385Y47932D01*
G01X544721Y42843D02*
X541361Y47130D01*
G01X548818Y44554D02*
G02X545753Y43635I-1707J123D01*
G01X550115Y44461D02*
G02X544726Y42837I-3004J216D01*
G01X548877Y45377D02*
X548818Y44554D01*
G01X550160Y45085D02*
X550115Y44461D01*
G01X552373Y54258D02*
X548877Y45377D01*
G01X553527Y53638D02*
X550160Y45085D01*
G01X558164Y62529D02*
X552373Y54258D01*
G01X559395Y62019D02*
X553527Y53638D01*
G01X563290Y91602D02*
X558164Y62529D01*
G01X564611Y91602D02*
X559395Y62019D01*
G01X547350Y70249D02*
G02X547286Y70186I-4216J4219D01*
G01X546430Y71169D02*
G02X543132Y69803I-3298J3298D01*
G01X551590Y74489D02*
X547350Y70249D01*
G01X550380Y75119D02*
X546430Y71169D01*
G01X537539Y70979D02*
X537313Y70753D01*
G01X537538Y72361D02*
G02X537539Y70979I-691J-692D01*
G01X538458Y73281D02*
G02Y70058I-1611J-1611D01*
G01X536439Y75300D02*
X538458Y73281D01*
G01X556780Y72156D02*
X559500Y87586D01*
G01X555547Y72657D02*
X558175Y87563D01*
G01X551900Y64900D02*
X556780Y72156D01*
G01X550865Y65705D02*
X555547Y72653D01*
G01X548900Y61900D02*
X551900Y64900D01*
G01X547496Y62336D02*
X550865Y65705D01*
G01X541600Y58962D02*
G03X547891Y61002I1J10718D01*
G01X547128Y62055D02*
G03X547496Y62336I-5530J7623D01*
G01X541600Y60262D02*
G03X547128Y62055I0J9418D01*
G01X537539Y70979D02*
X537313Y70753D01*
G01X538458Y73281D02*
G02Y70058I-1611J-1611D01*
G01X537538Y72361D02*
G02X537539Y70979I-691J-692D01*
G01X536439Y75300D02*
X538458Y73281D01*
G01X555547Y72657D02*
X558175Y87563D01*
G01X556780Y72156D02*
X559500Y87586D01*
G01X550865Y65705D02*
X555547Y72653D01*
G01X551900Y64900D02*
X556780Y72156D01*
G01X547496Y62336D02*
X550865Y65705D01*
G01X548900Y61900D02*
X551900Y64900D01*
G01X547128Y62055D02*
G03X547496Y62336I-5530J7623D01*
G01X541600Y58962D02*
G03X547891Y61002I1J10718D01*
G01X541600Y60262D02*
G03X547128Y62055I0J9418D01*
G01X541600Y58962D02*
G03X547891Y61002I1J10718D01*
G01X563020Y100621D02*
X564611Y91602D01*
G01X561699Y100621D02*
X563290Y91602D01*
G01X563657Y104237D02*
X563020Y100621D01*
G01X562422Y104723D02*
X561699Y100621D01*
G01X567172Y109649D02*
X563657Y104237D01*
G01X566298Y110692D02*
X562422Y104723D01*
G01X552594Y87676D02*
X550380Y75119D01*
G01X553915Y87676D02*
X551590Y74489D01*
G01X551198Y95607D02*
X552594Y87676D01*
G01X552519Y95607D02*
X553915Y87676D01*
G01X559323Y141681D02*
X551198Y95607D01*
G01X560558Y141194D02*
X552519Y95607D01*
G01X561699Y100621D02*
X563290Y91602D01*
G01X563020Y100621D02*
X564611Y91602D01*
G01X562422Y104723D02*
X561699Y100621D01*
G01X563657Y104237D02*
X563020Y100621D01*
G01X566298Y110692D02*
X562422Y104723D01*
G01X567172Y109649D02*
X563657Y104237D01*
G01X553915Y87676D02*
X551590Y74489D01*
G01X552594Y87676D02*
X550380Y75119D01*
G01X552519Y95607D02*
X553915Y87676D01*
G01X551198Y95607D02*
X552594Y87676D01*
G01X560558Y141194D02*
X552519Y95607D01*
G01X559323Y141681D02*
X551198Y95607D01*
G01X557453Y97218D02*
X560156Y109935D01*
G01X556123Y97218D02*
X558934Y110441D01*
G01X559500Y87586D02*
X557453Y97218D01*
G01X558175Y87563D02*
X556123Y97218D01*
G01D02*
X558934Y110441D01*
G01X557453Y97218D02*
X560156Y109935D01*
G01X558175Y87563D02*
X556123Y97218D01*
G01X559500Y87586D02*
X557453Y97218D01*
G01X574560Y112771D02*
X567172Y109649D01*
G01X574154Y114011D02*
X566298Y110692D01*
G01X562652Y146806D02*
X559323Y141681D01*
G01X563592Y145866D02*
X560558Y141194D01*
G01X574154Y114011D02*
X566298Y110692D01*
G01X574560Y112771D02*
X567172Y109649D01*
G01X563592Y145866D02*
X560558Y141194D01*
G01X562652Y146806D02*
X559323Y141681D01*
G01X552740Y128713D02*
X550369Y125062D01*
G01X553830Y128004D02*
X551309Y124122D01*
G01X555921Y143669D02*
X552740Y128713D01*
G01X557143Y143163D02*
X554012Y128442D01*
G01X568767Y138917D02*
X571600Y143280D01*
G01X567545Y139423D02*
X570660Y144220D01*
G01X563802Y115550D02*
X568767Y138917D01*
G01X562580Y116056D02*
X567545Y139423D01*
G01X560156Y109935D02*
X563802Y115550D01*
G01X558934Y110441D02*
X562580Y116056D01*
G01X553830Y128004D02*
X551309Y124122D01*
G01X552740Y128713D02*
X550369Y125062D01*
G01X557143Y143163D02*
X554012Y128442D01*
G01X555921Y143669D02*
X552740Y128713D01*
G01X567545Y139423D02*
X570660Y144220D01*
G01X568767Y138917D02*
X571600Y143280D01*
G01X562580Y116056D02*
X567545Y139423D01*
G01X563802Y115550D02*
X568767Y138917D01*
G01X558934Y110441D02*
X562580Y116056D01*
G01X560156Y109935D02*
X563802Y115550D01*
G01X578136Y156855D02*
X562652Y146806D01*
G01X578636Y155629D02*
X563592Y145866D01*
G01X578636Y155629D02*
X563592Y145866D01*
G01X578136Y156855D02*
X562652Y146806D01*
G01X559235Y148773D02*
X555921Y143669D01*
G01X560175Y147833D02*
X557143Y143163D01*
G01X576085Y159716D02*
X559235Y148773D01*
G01X576589Y158492D02*
X560175Y147833D01*
G01D02*
X557143Y143163D01*
G01X559235Y148773D02*
X555921Y143669D01*
G01X576589Y158492D02*
X560175Y147833D01*
G01X576085Y159716D02*
X559235Y148773D01*
G01X549169Y146827D02*
X576792Y164768D01*
G01X577298Y163545D02*
X549555Y145527D01*
G01X577298Y163545D02*
X549555Y145527D01*
G01X549169Y146827D02*
X576792Y164768D01*
G01X574331Y169950D02*
X559042Y160023D01*
G01X558536Y161245D02*
X573825Y171173D01*
G01X558536Y161245D02*
X573825Y171173D01*
G01X574331Y169950D02*
X559042Y160023D01*
G01X557369Y400444D02*
X585017Y395569D01*
G01X556882Y399209D02*
X585017Y394248D01*
G01X556882Y399209D02*
X585017Y394248D01*
G01X557369Y400444D02*
X585017Y395569D01*
G01X562424Y409315D02*
X582174Y405833D01*
G01Y404512D02*
X561938Y408080D01*
G01X582174Y404512D02*
X561938Y408080D01*
G01X562424Y409315D02*
X582174Y405833D01*
G01X558450Y403702D02*
X584759Y399063D01*
G01Y400384D02*
X558937Y404937D01*
G01D02*
X548240Y411883D01*
G01X558937Y404937D02*
X548240Y411883D01*
G01X584759Y400384D02*
X558937Y404937D01*
G01X558450Y403702D02*
X584759Y399063D01*
G01X537799Y418664D02*
X536415Y419563D01*
G01X541741Y416104D02*
X540357Y417003D01*
G01X545682Y413545D02*
X544299Y414443D01*
G01X537799Y418664D02*
X536415Y419563D01*
G01X541741Y416104D02*
X540357Y417003D01*
G01X545682Y413545D02*
X544299Y414443D01*
G01X566929Y805337D02*
X890529Y343190D01*
G01X891800Y343642D02*
X567902Y806216D01*
G01X562629Y809638D02*
X566929Y805337D01*
G01X567888Y806218D02*
X563629Y810477D01*
G01X552400Y824248D02*
X562629Y809638D01*
G01X563629Y810477D02*
X553700Y824658D01*
G01X566234Y816815D02*
X893640Y349235D01*
G01X567465Y817325D02*
X894871Y349745D01*
G01X563629Y810477D02*
X553700Y824658D01*
G01X552400Y824248D02*
X562629Y809638D01*
G01X567888Y806218D02*
X563629Y810477D01*
G01X562629Y809638D02*
X566929Y805337D01*
G01X891800Y343642D02*
X567902Y806216D01*
G01X566929Y805337D02*
X890529Y343190D01*
G01X567465Y817325D02*
X894871Y349745D01*
G01X566234Y816815D02*
X893640Y349235D01*
G01X552400Y841886D02*
Y824248D01*
G01X553700Y824658D02*
Y842000D01*
G01X551211Y848620D02*
X552400Y841886D01*
G01X553700Y842000D02*
X552442Y849130D01*
G01X539901Y864774D02*
X551211Y848620D01*
G01X552442Y849130D02*
X541201Y865184D01*
G01X564900Y824386D02*
X566234Y816815D01*
G01X566200Y824500D02*
X567465Y817325D01*
G01X564900Y841486D02*
Y824386D01*
G01X566200Y841600D02*
Y824500D01*
G01X563174Y851267D02*
X564900Y841486D01*
G01X564405Y851777D02*
X566200Y841600D01*
G01X552442Y849130D02*
X541201Y865184D01*
G01X539901Y864774D02*
X551211Y848620D01*
G01X553700Y842000D02*
X552442Y849130D01*
G01X551211Y848620D02*
X552400Y841886D01*
G01X553700Y824658D02*
Y842000D01*
G01X552400Y841886D02*
Y824248D01*
G01X566200Y824500D02*
X567465Y817325D01*
G01X564900Y824386D02*
X566234Y816815D01*
G01X566200Y841600D02*
Y824500D01*
G01X564900Y841486D02*
Y824386D01*
G01X564405Y851777D02*
X566200Y841600D01*
G01X563174Y851267D02*
X564900Y841486D01*
G01X565098Y863502D02*
X576312Y847486D01*
G01X566398Y863913D02*
X577543Y847996D01*
G01X565098Y872882D02*
Y863502D01*
G01X566398Y872882D02*
Y863913D01*
G01D02*
X577543Y847996D01*
G01X565098Y863502D02*
X576312Y847486D01*
G01X566398Y872882D02*
Y863913D01*
G01X565098Y872882D02*
Y863502D01*
G01X539901Y872882D02*
Y864774D01*
G01X541201Y865184D02*
Y872882D01*
G01X552500Y866512D02*
X563174Y851267D01*
G01X553800Y866923D02*
X564405Y851777D01*
G01X552500Y872882D02*
Y866512D01*
G01X553800Y872882D02*
Y866923D01*
G01X541201Y865184D02*
Y872882D01*
G01X539901D02*
Y864774D01*
G01X553800Y866923D02*
X564405Y851777D01*
G01X552500Y866512D02*
X563174Y851267D01*
G01X553800Y872882D02*
Y866923D01*
G01X552500Y872882D02*
Y866512D01*
G01X600625Y62357D02*
X605387Y69986D01*
G01X599546Y63084D02*
X604150Y70461D01*
G01X598366Y57861D02*
G02X600599Y62320I14625J-4535D01*
G01X597124Y58246D02*
G02X599546Y63084I15868J-4918D01*
G01X597367Y54646D02*
X598366Y57861D01*
G01X596125Y55031D02*
X597124Y58246D01*
G01X594742Y44280D02*
G02X597367Y54644I97550J-19193D01*
G01X593466Y44531D02*
G02X596125Y55031I98827J-19440D01*
G01X588970Y42224D02*
G03X594742Y44280I2275J2744D01*
G01X589873Y43168D02*
G03X593466Y44531I1372J1800D01*
G01X584147Y47741D02*
X588970Y42224D01*
G01X585126Y48597D02*
X589873Y43168D01*
G01X583948Y50518D02*
G03X584029Y47899I2245J-1241D01*
G01X585086Y49889D02*
G03X585126Y48597I1107J-612D01*
G01X584470Y51676D02*
G02X583947Y50519I-7326J2615D01*
G01X585695Y51240D02*
G02X585086Y49889I-8555J3044D01*
G01X588820Y70179D02*
X596920Y78279D01*
G01X589740Y69260D02*
X598130Y77649D01*
G01X591300Y75300D02*
X584787Y73123D01*
G01X581717Y72681D02*
X584218Y74304D01*
G01X584787Y73123D02*
X582661Y71743D01*
G01X580157Y70244D02*
X581717Y72681D01*
G01X582661Y71743D02*
X581176Y69424D01*
G01X579757Y69844D02*
X580157Y70244D01*
G01X581176Y69424D02*
X580577Y68825D01*
G01X599546Y63084D02*
X604150Y70461D01*
G01X600625Y62357D02*
X605387Y69986D01*
G01X597124Y58246D02*
G02X599546Y63084I15868J-4918D01*
G01X598366Y57861D02*
G02X600599Y62320I14625J-4535D01*
G01X596125Y55031D02*
X597124Y58246D01*
G01X597367Y54646D02*
X598366Y57861D01*
G01X593466Y44531D02*
G02X596125Y55031I98827J-19440D01*
G01X594742Y44280D02*
G02X597367Y54644I97550J-19193D01*
G01X589873Y43168D02*
G03X593466Y44531I1372J1800D01*
G01X588970Y42224D02*
G03X594742Y44280I2275J2744D01*
G01X585126Y48597D02*
X589873Y43168D01*
G01X584147Y47741D02*
X588970Y42224D01*
G01X585086Y49889D02*
G03X585126Y48597I1107J-612D01*
G01X583948Y50518D02*
G03X584029Y47899I2245J-1241D01*
G01X585695Y51240D02*
G02X585086Y49889I-8555J3044D01*
G01X584470Y51676D02*
G02X583947Y50519I-7326J2615D01*
G01X589740Y69260D02*
X598130Y77649D01*
G01X588820Y70179D02*
X596920Y78279D01*
G01X581176Y69424D02*
X580577Y68825D01*
G01X579757Y69844D02*
X580157Y70244D01*
G01X582661Y71743D02*
X581176Y69424D01*
G01X580157Y70244D02*
X581717Y72681D01*
G01X584787Y73123D02*
X582661Y71743D01*
G01X581717Y72681D02*
X584218Y74304D01*
G01X591300Y75300D02*
X584787Y73123D01*
G01X601744Y73594D02*
X603700Y84686D01*
G01X600513Y74104D02*
X602400Y84806D01*
G01X596494Y66097D02*
X601744Y73594D01*
G01X595531Y66990D02*
X600513Y74104D01*
G01X594342Y64334D02*
X596494Y66097D01*
G01X593380Y65228D02*
X595531Y66990D01*
G01X590974Y60950D02*
X594303Y64280D01*
G01X590054Y61870D02*
X593304Y65120D01*
G01X586986Y59301D02*
G03X590974Y60950I5J5634D01*
G01X586990Y60601D02*
G03X590054Y61870I0J4333D01*
G01X571990Y45173D02*
G02X571002Y44469I-2593J2593D01*
G01X571069Y46092D02*
G02X570433Y45638I-1671J1668D01*
G01X571990Y45173D02*
G02X571002Y44469I-2593J2593D01*
G01X574877Y49900D02*
X571069Y46092D01*
G01X575797Y48980D02*
X571990Y45173D01*
G01X576001Y50699D02*
G03X574877Y49900I1800J-3723D01*
G01X576567Y49527D02*
G03X575797Y48980I1233J-2552D01*
G01X600513Y74104D02*
X602400Y84806D01*
G01X601744Y73594D02*
X603700Y84686D01*
G01X595531Y66990D02*
X600513Y74104D01*
G01X596494Y66097D02*
X601744Y73594D01*
G01X593380Y65228D02*
X595531Y66990D01*
G01X594342Y64334D02*
X596494Y66097D01*
G01X590054Y61870D02*
X593304Y65120D01*
G01X590974Y60950D02*
X594303Y64280D01*
G01X586990Y60601D02*
G03X590054Y61870I0J4333D01*
G01X586986Y59301D02*
G03X590974Y60950I5J5634D01*
G01X571069Y46092D02*
G02X570433Y45638I-1671J1668D01*
G01X571990Y45173D02*
G02X571002Y44469I-2593J2593D01*
G01X571069Y46092D02*
G02X570433Y45638I-1671J1668D01*
G01X575797Y48980D02*
X571990Y45173D01*
G01X574877Y49900D02*
X571069Y46092D01*
G01X576567Y49527D02*
G03X575797Y48980I1233J-2552D01*
G01X576001Y50699D02*
G03X574877Y49900I1800J-3723D01*
G01X600342Y107917D02*
X604267Y113525D01*
G01X601573Y107407D02*
X605201Y112591D01*
G01X597907Y94106D02*
X600342Y107917D01*
G01X599228Y94106D02*
X601573Y107407D01*
G01X598810Y88993D02*
X597907Y94106D01*
G01X600131Y88993D02*
X599228Y94106D01*
G01X596920Y78279D02*
X598810Y88993D01*
G01X598130Y77649D02*
X600131Y88993D01*
G01X593768Y94782D02*
X596679Y111313D01*
G01X597910Y110805D02*
X595089Y94782D01*
G01X594835Y88733D02*
X593768Y94782D01*
G01X595089D02*
X596156Y88733D01*
G01X593384Y80501D02*
X594835Y88733D01*
G01X596156D02*
X594644Y80158D01*
G01X592789Y78908D02*
X593384Y80501D01*
G01X594644Y80158D02*
X593921Y78223D01*
G01X590561Y76425D02*
X592789Y78908D01*
G01X593921Y78223D02*
X591300Y75300D01*
G01X584218Y74304D02*
X590561Y76425D01*
G01X601573Y107407D02*
X605201Y112591D01*
G01X600342Y107917D02*
X604267Y113525D01*
G01X599228Y94106D02*
X601573Y107407D01*
G01X597907Y94106D02*
X600342Y107917D01*
G01X600131Y88993D02*
X599228Y94106D01*
G01X598810Y88993D02*
X597907Y94106D01*
G01X598130Y77649D02*
X600131Y88993D01*
G01X596920Y78279D02*
X598810Y88993D01*
G01X584218Y74304D02*
X590561Y76425D01*
G01X593921Y78223D02*
X591300Y75300D01*
G01X590561Y76425D02*
X592789Y78908D01*
G01X594644Y80158D02*
X593921Y78223D01*
G01X592789Y78908D02*
X593384Y80501D01*
G01X596156Y88733D02*
X594644Y80158D01*
G01X593384Y80501D02*
X594835Y88733D01*
G01X595089Y94782D02*
X596156Y88733D01*
G01X594835D02*
X593768Y94782D01*
G01X597910Y110805D02*
X595089Y94782D01*
G01X593768D02*
X596679Y111313D01*
G01X603331Y104799D02*
X608246Y111817D01*
G01X602400Y99514D02*
X603331Y104799D01*
G01X602400Y84806D02*
Y99514D01*
G01X603331Y104799D02*
X608246Y111817D01*
G01X602400Y99514D02*
X603331Y104799D01*
G01X602400Y84806D02*
Y99514D01*
G01X598358Y113723D02*
X612892Y123406D01*
G01X613837Y122472D02*
X599285Y112777D01*
G01X596679Y111313D02*
X598358Y113723D01*
G01X599285Y112777D02*
X597910Y110805D01*
G01X599285Y112777D02*
X597910Y110805D01*
G01X596679Y111313D02*
X598358Y113723D01*
G01X613837Y122472D02*
X599285Y112777D01*
G01X598358Y113723D02*
X612892Y123406D01*
G01X601432Y119157D02*
X574560Y112771D01*
G01X600912Y120371D02*
X574154Y114011D01*
G01X610118Y124798D02*
X601432Y119157D01*
G01X609178Y125738D02*
X600912Y120371D01*
G01D02*
X574154Y114011D01*
G01X601432Y119157D02*
X574560Y112771D01*
G01X609178Y125738D02*
X600912Y120371D01*
G01X610118Y124798D02*
X601432Y119157D01*
G01X648146Y170976D02*
X578136Y156855D01*
G01X648147Y169650D02*
X578636Y155629D01*
G01X648147Y169650D02*
X578636Y155629D01*
G01X648146Y170976D02*
X578136Y156855D01*
G01X648660Y174799D02*
X576085Y159716D01*
G01X648665Y173472D02*
X576589Y158492D01*
G01X595291Y143448D02*
X605043Y145522D01*
G01X595291Y144778D02*
X604537Y146744D01*
G01X580618Y146567D02*
X595291Y143448D01*
G01X580618Y147897D02*
X595291Y144778D01*
G01X574739Y145318D02*
X580618Y146567D01*
G01X574233Y146540D02*
X580618Y147897D01*
G01X571600Y143280D02*
X574739Y145318D01*
G01X570660Y144220D02*
X574233Y146540D01*
G01X648665Y173472D02*
X576589Y158492D01*
G01X648660Y174799D02*
X576085Y159716D01*
G01X595291Y144778D02*
X604537Y146744D01*
G01X595291Y143448D02*
X605043Y145522D01*
G01X580618Y147897D02*
X595291Y144778D01*
G01X580618Y146567D02*
X595291Y143448D01*
G01X574233Y146540D02*
X580618Y147897D01*
G01X574739Y145318D02*
X580618Y146567D01*
G01X570660Y144220D02*
X574233Y146540D01*
G01X571600Y143280D02*
X574739Y145318D01*
G01X576792Y164768D02*
X647974Y179832D01*
G01X647973Y178502D02*
X577298Y163545D01*
G01X647973Y178502D02*
X577298Y163545D01*
G01X576792Y164768D02*
X647974Y179832D01*
G01X645984Y185114D02*
X574331Y169950D01*
G01X573825Y171173D02*
X645985Y186444D01*
G01X573825Y171173D02*
X645985Y186444D01*
G01X645984Y185114D02*
X574331Y169950D01*
G01X585017Y395569D02*
X644530Y406063D01*
G01X585017Y394248D02*
X610607Y398760D01*
G01X585017Y395569D02*
X644530Y406063D01*
G01X585017Y395569D02*
X644530Y406063D01*
G01X585017Y395569D02*
X644530Y406063D01*
G01X585017Y394248D02*
X610607Y398760D01*
G01X585017Y395569D02*
X644530Y406063D01*
G01X645548Y415687D02*
X582174Y404512D01*
G01X645548Y415687D02*
X582174Y404512D01*
G01X645548Y415687D02*
X582174Y404512D01*
G01X645548Y415687D02*
X582174Y404512D01*
G01X645548Y415687D02*
X582174Y404512D01*
G01X645548Y415687D02*
X582174Y404512D01*
G01X597202Y408483D02*
X603226Y409545D01*
G01X645548Y415687D02*
X582174Y404512D01*
G01X590870Y407366D02*
X594120Y407939D01*
G01X645548Y415687D02*
X582174Y404512D01*
G01Y405833D02*
X587788Y406823D01*
G01X645548Y415687D02*
X582174Y404512D01*
G01X645548Y415687D02*
X582174Y404512D01*
G01X597202Y408483D02*
X603226Y409545D01*
G01X590870Y407366D02*
X594120Y407939D01*
G01X582174Y405833D02*
X587788Y406823D01*
G01X584759Y399063D02*
X646136Y409884D01*
G01X586384Y400670D02*
X584759Y400384D01*
G01X591013Y401487D02*
X589388Y401200D01*
G01X595641Y402303D02*
X594016Y402016D01*
G01X600270Y403119D02*
X598645Y402832D01*
G01X646136Y411205D02*
X603273Y403648D01*
G01X586384Y400670D02*
X584759Y400384D01*
G01Y399063D02*
X646136Y409884D01*
G01X591013Y401487D02*
X589388Y401200D01*
G01X584759Y399063D02*
X646136Y409884D01*
G01X595641Y402303D02*
X594016Y402016D01*
G01X584759Y399063D02*
X646136Y409884D01*
G01X600270Y403119D02*
X598645Y402832D01*
G01X584759Y399063D02*
X646136Y409884D01*
G01Y411205D02*
X603273Y403648D01*
G01X584759Y399063D02*
X646136Y409884D01*
G01X592916Y489536D02*
X684661Y425296D01*
G01X590352Y491332D02*
X591383Y491514D01*
G01X589001Y492278D02*
X590352Y491332D01*
G01X586437Y494074D02*
X587467Y494255D01*
G01X585085Y495020D02*
X586437Y494074D01*
G01X582521Y496815D02*
X583552Y496997D01*
G01X592916Y489536D02*
X684661Y425296D01*
G01X590352Y491332D02*
X591383Y491514D01*
G01X589001Y492278D02*
X590352Y491332D01*
G01X586437Y494074D02*
X587467Y494255D01*
G01X585085Y495020D02*
X586437Y494074D01*
G01X582521Y496815D02*
X583552Y496997D01*
G01X580615Y805618D02*
X897922Y352465D01*
G01X581846Y806128D02*
X899153Y352975D01*
G01X581846Y806128D02*
X899153Y352975D01*
G01X580615Y805618D02*
X897922Y352465D01*
G01X592269Y802090D02*
X622889Y758360D01*
G01X593500Y802600D02*
X623823Y759294D01*
G01X590400Y812691D02*
X592269Y802090D01*
G01X591700Y812805D02*
X593500Y802600D01*
G01X590400Y840786D02*
Y812691D01*
G01X591700Y840900D02*
Y812805D01*
G01X593500Y802600D02*
X623823Y759294D01*
G01X592269Y802090D02*
X622889Y758360D01*
G01X591700Y812805D02*
X593500Y802600D01*
G01X590400Y812691D02*
X592269Y802090D01*
G01X591700Y840900D02*
Y812805D01*
G01X590400Y840786D02*
Y812691D01*
G01X577600Y822720D02*
X580615Y805618D01*
G01X578900Y822834D02*
X581846Y806128D01*
G01X578900Y822834D02*
X581846Y806128D01*
G01X577600Y822720D02*
X580615Y805618D01*
G01X603001Y824931D02*
X910484Y385798D01*
G01X603001Y840986D02*
Y824931D01*
G01X601300Y850630D02*
X603001Y840986D01*
G01X602531Y851140D02*
X604301Y841100D01*
G01X603001Y824931D02*
X910484Y385798D01*
G01X603001Y840986D02*
Y824931D01*
G01X602531Y851140D02*
X604301Y841100D01*
G01X601300Y850630D02*
X603001Y840986D01*
G01X589316Y846927D02*
X590400Y840786D01*
G01X590547Y847437D02*
X591700Y840900D01*
G01X577697Y863522D02*
X589316Y846927D01*
G01X578997Y863932D02*
X590547Y847437D01*
G01D02*
X591700Y840900D01*
G01X589316Y846927D02*
X590400Y840786D01*
G01X578997Y863932D02*
X590547Y847437D01*
G01X577697Y863522D02*
X589316Y846927D01*
G01X577600Y840186D02*
Y822720D01*
G01X578900Y840300D02*
Y822834D01*
G01X576312Y847486D02*
X577600Y840186D01*
G01X577543Y847996D02*
X578900Y840300D01*
G01D02*
Y822834D01*
G01X577600Y840186D02*
Y822720D01*
G01X577543Y847996D02*
X578900Y840300D01*
G01X576312Y847486D02*
X577600Y840186D01*
G01X602894Y866970D02*
X605536Y863196D01*
G01X602894Y872882D02*
Y866970D01*
G01D02*
X605536Y863196D01*
G01X602894Y872882D02*
Y866970D01*
G01X590295Y866348D02*
X601300Y850630D01*
G01X591595Y866759D02*
X602531Y851140D01*
G01X590295Y872882D02*
Y866348D01*
G01X591595Y872882D02*
Y866759D01*
G01D02*
X602531Y851140D01*
G01X590295Y866348D02*
X601300Y850630D01*
G01X591595Y872882D02*
Y866759D01*
G01X590295Y872882D02*
Y866348D01*
G01X577697Y873900D02*
Y863522D01*
G01X578997Y872882D02*
Y863932D01*
G01Y872882D02*
Y863932D01*
G01X577697Y873900D02*
Y863522D01*
G01X632961Y56000D02*
X630564Y53603D01*
G01X632800Y53999D02*
X631107Y52306D01*
G01X633800Y55000D02*
X632800Y54000D01*
G01X642513Y62689D02*
X632961Y56000D01*
G01X643447Y61755D02*
X633800Y55000D01*
G01X631276Y69224D02*
X640216Y78163D01*
G01X632195Y68304D02*
X641426Y77533D01*
G01X631083Y69020D02*
G02X631276Y69224I3674J-3283D01*
G01X632053Y68153D02*
G02X632195Y68304I2712J-2408D01*
G01X628529Y74165D02*
X634100Y75300D01*
G01X625800Y73800D02*
X627995Y75383D01*
G01X626762Y72890D02*
X628529Y74165D01*
G01X623812Y70692D02*
X625800Y73800D01*
G01X624832Y69872D02*
X626762Y72890D01*
G01X622138Y69018D02*
X623812Y70692D01*
G01X623487Y68527D02*
X624832Y69872D01*
G01X633517Y61424D02*
X639714Y66706D01*
G01X634152Y60257D02*
X640684Y65824D01*
G01X627244Y59541D02*
X633517Y61424D01*
G01X627618Y58295D02*
X634152Y60257D01*
G01X625588Y58898D02*
G02X627244Y59541I4906J-10180D01*
G01X626153Y57726D02*
G02X627618Y58295I4342J-9008D01*
G01X624868Y58550D02*
X625588Y58898D01*
G01X625429Y57377D02*
X626153Y57726D01*
G01X622447Y54421D02*
G02X624868Y58550I4211J305D01*
G01X623744Y54515D02*
G02X625429Y57377I2914J211D01*
G01X622170Y53520D02*
G03X622447Y54421I-1022J807D01*
G01X623190Y52714D02*
G03X623744Y54515I-2041J1614D01*
G01X621626Y52665D02*
G02X622170Y53520I4430J-2218D01*
G01X622789Y52083D02*
G02X623190Y52714I3268J-1634D01*
G01X621219Y51851D02*
X621626Y52665D01*
G01X622506Y51516D02*
X622789Y52083D01*
G01X632800Y53999D02*
X631107Y52306D01*
G01X632961Y56000D02*
X630564Y53603D01*
G01X633800Y55000D02*
X632800Y54000D01*
G01X632961Y56000D02*
X630564Y53603D01*
G01X643447Y61755D02*
X633800Y55000D01*
G01X642513Y62689D02*
X632961Y56000D01*
G01X632195Y68304D02*
X641426Y77533D01*
G01X631276Y69224D02*
X640216Y78163D01*
G01X632053Y68153D02*
G02X632195Y68304I2712J-2408D01*
G01X631083Y69020D02*
G02X631276Y69224I3674J-3283D01*
G01X628529Y74165D02*
X634100Y75300D01*
G01X626762Y72890D02*
X628529Y74165D01*
G01X625800Y73800D02*
X627995Y75383D01*
G01X624832Y69872D02*
X626762Y72890D01*
G01X623812Y70692D02*
X625800Y73800D01*
G01X623487Y68527D02*
X624832Y69872D01*
G01X622138Y69018D02*
X623812Y70692D01*
G01X634152Y60257D02*
X640684Y65824D01*
G01X633517Y61424D02*
X639714Y66706D01*
G01X627618Y58295D02*
X634152Y60257D01*
G01X627244Y59541D02*
X633517Y61424D01*
G01X626153Y57726D02*
G02X627618Y58295I4342J-9008D01*
G01X625588Y58898D02*
G02X627244Y59541I4906J-10180D01*
G01X625429Y57377D02*
X626153Y57726D01*
G01X624868Y58550D02*
X625588Y58898D01*
G01X623744Y54515D02*
G02X625429Y57377I2914J211D01*
G01X622447Y54421D02*
G02X624868Y58550I4211J305D01*
G01X623190Y52714D02*
G03X623744Y54515I-2041J1614D01*
G01X622170Y53520D02*
G03X622447Y54421I-1022J807D01*
G01X622789Y52083D02*
G02X623190Y52714I3268J-1634D01*
G01X621626Y52665D02*
G02X622170Y53520I4430J-2218D01*
G01X622506Y51516D02*
X622789Y52083D01*
G01X621219Y51851D02*
X621626Y52665D01*
G01X605387Y69986D02*
X608069Y85191D01*
G01X604150Y70461D02*
X606750Y85200D01*
G01X604150Y70461D02*
X606750Y85200D01*
G01X605387Y69986D02*
X608069Y85191D01*
G01X636588Y96529D02*
X638660Y104890D01*
G01X638409Y87331D02*
X636588Y96529D01*
G01X637219Y81070D02*
X638409Y87331D01*
G01X635968Y78955D02*
X637220Y81070D01*
G01X636500Y77300D02*
X638455Y80604D01*
G01X635782Y78641D02*
X635968Y78955D01*
G01X636500Y77300D02*
X638455Y80604D01*
G01X635662Y78438D02*
X635782Y78641D01*
G01X636500Y77300D02*
X638455Y80604D01*
G01X635495Y78155D02*
X635662Y78438D01*
G01X636500Y77300D02*
X638455Y80604D01*
G01X633519Y76509D02*
X635495Y78155D01*
G01X634100Y75300D02*
X636500Y77300D01*
G01X627995Y75383D02*
X633519Y76509D01*
G01X636588Y96529D02*
X638660Y104890D01*
G01X638409Y87331D02*
X636588Y96529D01*
G01X637219Y81070D02*
X638409Y87331D01*
G01X636500Y77300D02*
X638455Y80604D01*
G01X635968Y78955D02*
X637220Y81070D01*
G01X635782Y78641D02*
X635968Y78955D01*
G01X635662Y78438D02*
X635782Y78641D01*
G01X635495Y78155D02*
X635662Y78438D01*
G01X634100Y75300D02*
X636500Y77300D01*
G01X633519Y76509D02*
X635495Y78155D01*
G01X627995Y75383D02*
X633519Y76509D01*
G01X611319Y107684D02*
X614851Y110156D01*
G01X608611Y103816D02*
X611319Y107684D01*
G01X607435Y104404D02*
X610385Y108618D01*
G01X607004Y98904D02*
X608611Y103816D01*
G01X605700Y99100D02*
X607435Y104404D01*
G01X607123Y92274D02*
X607004Y98904D01*
G01X605824Y92149D02*
X605700Y99100D01*
G01X608050Y87014D02*
X607123Y92274D01*
G01X606750Y86900D02*
X605824Y92149D01*
G01X608050Y85300D02*
Y87014D01*
G01X606750Y85200D02*
Y86900D01*
G01X611319Y107684D02*
X614851Y110156D01*
G01X607435Y104404D02*
X610385Y108618D01*
G01X608611Y103816D02*
X611319Y107684D01*
G01X605700Y99100D02*
X607435Y104404D01*
G01X607004Y98904D02*
X608611Y103816D01*
G01X605824Y92149D02*
X605700Y99100D01*
G01X607123Y92274D02*
X607004Y98904D01*
G01X606750Y86900D02*
X605824Y92149D01*
G01X608050Y87014D02*
X607123Y92274D01*
G01X606750Y85200D02*
Y86900D01*
G01X608050Y85300D02*
Y87014D01*
G01X604562Y104289D02*
X609166Y110864D01*
G01X603700Y99400D02*
X604562Y104289D01*
G01X603700Y84686D02*
Y99400D01*
G01X604562Y104289D02*
X609166Y110864D01*
G01X603700Y99400D02*
X604562Y104289D01*
G01X603700Y84686D02*
Y99400D01*
G01X618436Y111643D02*
X651813Y118739D01*
G01X618049Y112890D02*
X651307Y119961D01*
G01X614851Y110156D02*
X618436Y111643D01*
G01X614221Y111303D02*
X618049Y112890D01*
G01X610385Y108618D02*
X614221Y111303D01*
G01X611595Y118654D02*
X647641Y126319D01*
G01X612124Y117437D02*
X648147Y125097D01*
G01X604267Y113525D02*
X611595Y118654D01*
G01X605201Y112591D02*
X612124Y117437D01*
G01X615968Y128142D02*
X619474Y144636D01*
G01X620696Y144130D02*
X617190Y127636D01*
G01X612892Y123406D02*
X615968Y128142D01*
G01X617190Y127636D02*
X613837Y122472D01*
G01X618049Y112890D02*
X651307Y119961D01*
G01X618436Y111643D02*
X651813Y118739D01*
G01X614221Y111303D02*
X618049Y112890D01*
G01X614851Y110156D02*
X618436Y111643D01*
G01X610385Y108618D02*
X614221Y111303D01*
G01X612124Y117437D02*
X648147Y125097D01*
G01X611595Y118654D02*
X647641Y126319D01*
G01X605201Y112591D02*
X612124Y117437D01*
G01X604267Y113525D02*
X611595Y118654D01*
G01X617190Y127636D02*
X613837Y122472D01*
G01X612892Y123406D02*
X615968Y128142D01*
G01X620696Y144130D02*
X617190Y127636D01*
G01X615968Y128142D02*
X619474Y144636D01*
G01X614929Y114607D02*
X650932Y122259D01*
G01X614423Y115829D02*
X650426Y123481D01*
G01X609166Y110864D02*
X614929Y114607D01*
G01X608246Y111817D02*
X614423Y115829D01*
G01X611869Y127494D02*
X610118Y124798D01*
G01X610647Y128000D02*
X609178Y125738D01*
G01X613355Y134487D02*
X611869Y127494D01*
G01X612025Y134487D02*
X610647Y128000D01*
G01X612565Y138206D02*
X613355Y134487D01*
G01X611235Y138206D02*
X612025Y134487D01*
G01X613614Y143149D02*
X612565Y138206D01*
G01X612392Y143655D02*
X611235Y138206D01*
G01X614423Y115829D02*
X650426Y123481D01*
G01X614929Y114607D02*
X650932Y122259D01*
G01X608246Y111817D02*
X614423Y115829D01*
G01X609166Y110864D02*
X614929Y114607D01*
G01X610647Y128000D02*
X609178Y125738D01*
G01X611869Y127494D02*
X610118Y124798D01*
G01X612025Y134487D02*
X610647Y128000D01*
G01X613355Y134487D02*
X611869Y127494D01*
G01X611235Y138206D02*
X612025Y134487D01*
G01X612565Y138206D02*
X613355Y134487D01*
G01X612392Y143655D02*
X611235Y138206D01*
G01X613614Y143149D02*
X612565Y138206D01*
G01X634814Y156292D02*
X638723Y157124D01*
G01Y155794D02*
X635320Y155070D01*
G01X621380Y147571D02*
X634814Y156292D01*
G01X635320Y155070D02*
X622320Y146631D01*
G01X619474Y144636D02*
X621380Y147571D01*
G01X622320Y146631D02*
X620696Y144130D01*
G01X622320Y146631D02*
X620696Y144130D01*
G01X619474Y144636D02*
X621380Y147571D01*
G01X635320Y155070D02*
X622320Y146631D01*
G01X621380Y147571D02*
X634814Y156292D01*
G01X638723Y155794D02*
X635320Y155070D01*
G01X634814Y156292D02*
X638723Y157124D01*
G01X615407Y145909D02*
X613614Y143149D01*
G01X616259Y149609D02*
X612392Y143655D01*
G01X617199Y148669D02*
X615408Y145911D01*
G01X616259Y149609D02*
X612392Y143655D01*
G01X632127Y158366D02*
X617199Y148669D01*
G01X631621Y159588D02*
X616259Y149609D01*
G01X650006Y162164D02*
X632127Y158366D01*
G01X650005Y163493D02*
X631621Y159588D01*
G01X616259Y149609D02*
X612392Y143655D01*
G01X615407Y145909D02*
X613614Y143149D01*
G01X617199Y148669D02*
X615408Y145911D01*
G01X631621Y159588D02*
X616259Y149609D01*
G01X632127Y158366D02*
X617199Y148669D01*
G01X650005Y163493D02*
X631621Y159588D01*
G01X650006Y162164D02*
X632127Y158366D01*
G01X630330Y161943D02*
X648125Y165726D01*
G01X629824Y163165D02*
X648117Y167054D01*
G01X605043Y145522D02*
X630330Y161943D01*
G01X604537Y146744D02*
X629824Y163165D01*
G01D02*
X648117Y167054D01*
G01X630330Y161943D02*
X648125Y165726D01*
G01X604537Y146744D02*
X629824Y163165D01*
G01X605043Y145522D02*
X630330Y161943D01*
G01X623163Y400974D02*
X644530Y404742D01*
G01X618436Y400140D02*
X620061Y400427D01*
G01X613709Y399307D02*
X615334Y399593D01*
G01X623163Y400974D02*
X644530Y404742D01*
G01X618436Y400140D02*
X620061Y400427D01*
G01X613709Y399307D02*
X615334Y399593D01*
G01X611016Y410919D02*
X617349Y412035D01*
G01X606309Y410089D02*
X607934Y410375D01*
G01X611016Y410919D02*
X617349Y412035D01*
G01X606309Y410089D02*
X607934Y410375D01*
G01X636230Y415365D02*
X645548Y417008D01*
G01X629846Y414239D02*
X633148Y414821D01*
G01X625139Y413409D02*
X626764Y413695D01*
G01X620431Y412579D02*
X622056Y412865D01*
G01X636230Y415365D02*
X645548Y417008D01*
G01X629846Y414239D02*
X633148Y414821D01*
G01X625139Y413409D02*
X626764Y413695D01*
G01X620431Y412579D02*
X622056Y412865D01*
G01X622889Y758360D02*
X661566Y731279D01*
G01X622889Y758360D02*
X661566Y731279D01*
G01X604301Y825341D02*
X911715Y386308D01*
G01X604301Y825341D02*
X911715Y386308D01*
G01X623823Y759294D02*
X662500Y732213D01*
G01X623823Y759294D02*
X662500Y732213D01*
G01X629300Y822957D02*
X650911Y792093D01*
G01X628000Y822547D02*
X649680Y791583D01*
G01X628000Y822547D02*
X649680Y791583D01*
G01X629300Y822957D02*
X650911Y792093D01*
G01X635866Y851466D02*
X646005Y836986D01*
G01X635866Y851466D02*
X646005Y836986D01*
G01X629300Y840000D02*
Y822957D01*
G01X628000Y839886D02*
Y822547D01*
G01X628014Y847290D02*
X629300Y840000D01*
G01X626783Y846780D02*
X628000Y839886D01*
G01X625603Y850733D02*
X628014Y847290D01*
G01X624669Y849799D02*
X626783Y846780D01*
G01X605536Y863196D02*
X624669Y849799D01*
G01X628000Y839886D02*
Y822547D01*
G01X629300Y840000D02*
Y822957D01*
G01X626783Y846780D02*
X628000Y839886D01*
G01X628014Y847290D02*
X629300Y840000D01*
G01X624669Y849799D02*
X626783Y846780D01*
G01X625603Y850733D02*
X628014Y847290D01*
G01X605536Y863196D02*
X624669Y849799D01*
G01X604301Y841100D02*
Y825341D01*
G01Y841100D02*
Y825341D01*
G01X635186Y859880D02*
X646137Y857949D01*
G01X635696Y861111D02*
X646647Y859180D01*
G01X630066Y863466D02*
X635186Y859880D01*
G01X631000Y864400D02*
X635696Y861111D01*
G01X628090Y866289D02*
X630066Y863466D01*
G01X629390Y866699D02*
X631000Y864400D01*
G01X628090Y872882D02*
Y866289D01*
G01X629390Y872882D02*
Y866699D01*
G01X636800Y852400D02*
X647236Y837496D01*
G01X619816Y864293D02*
X636800Y852400D01*
G01X618882Y863359D02*
X635866Y851466D01*
G01X616792Y868611D02*
X619816Y864293D01*
G01X615492Y868201D02*
X618882Y863359D01*
G01X616792Y872882D02*
Y868611D01*
G01X615492Y872882D02*
Y868201D01*
G01X635696Y861111D02*
X646647Y859180D01*
G01X635186Y859880D02*
X646137Y857949D01*
G01X631000Y864400D02*
X635696Y861111D01*
G01X630066Y863466D02*
X635186Y859880D01*
G01X629390Y866699D02*
X631000Y864400D01*
G01X628090Y866289D02*
X630066Y863466D01*
G01X629390Y872882D02*
Y866699D01*
G01X628090Y872882D02*
Y866289D01*
G01X636800Y852400D02*
X647236Y837496D01*
G01X618882Y863359D02*
X635866Y851466D01*
G01X619816Y864293D02*
X636800Y852400D01*
G01X615492Y868201D02*
X618882Y863359D01*
G01X616792Y868611D02*
X619816Y864293D01*
G01X615492Y872882D02*
Y868201D01*
G01X616792Y872882D02*
Y868611D01*
G01X606470Y864130D02*
X625603Y850733D01*
G01X604194Y867380D02*
X606470Y864130D01*
G01X604194Y872882D02*
Y867380D01*
G01X606470Y864130D02*
X625603Y850733D01*
G01X604194Y867380D02*
X606470Y864130D01*
G01X604194Y872882D02*
Y867380D01*
G01X668668Y73726D02*
X671249Y75581D01*
G01X669713Y72876D02*
X671779Y74360D01*
G01X667338Y70733D02*
X668668Y73726D01*
G01X668443Y70017D02*
X669713Y72876D01*
G01X666177Y69440D02*
X667338Y70733D01*
G01X665981Y67276D02*
X668443Y70017D01*
G01X665014Y68145D02*
X666177Y69440D01*
G01X665981Y67276D02*
X668443Y70017D01*
G01X664870Y68034D02*
G03X665014Y68145I-245J466D01*
G01X665483Y66886D02*
G03X665981Y67276I-861J1612D01*
G01X664585Y67880D02*
X664870Y68033D01*
G01X665199Y66734D02*
X665483Y66886D01*
G01X668745Y57805D02*
X672265Y59826D01*
G01X671090Y57651D02*
X672785Y58625D01*
G01X670471Y57296D02*
X671090Y57651D01*
G01X669393Y56677D02*
X670471Y57296D01*
G01X668740Y57802D02*
X668745Y57805D01*
G01X669393Y56677D02*
X670471Y57296D01*
G01X668496Y57662D02*
X668740Y57802D01*
G01X669393Y56677D02*
X670471Y57296D01*
G01X665515Y53615D02*
X668495Y57663D01*
G01X666564Y52844D02*
X669381Y56671D01*
G01X665464Y53544D02*
X665512Y53609D01*
G01X666564Y52844D02*
X669381Y56671D01*
G01X669713Y72876D02*
X671779Y74360D01*
G01X668668Y73726D02*
X671249Y75581D01*
G01X668443Y70017D02*
X669713Y72876D01*
G01X667338Y70733D02*
X668668Y73726D01*
G01X665981Y67276D02*
X668443Y70017D01*
G01X666177Y69440D02*
X667338Y70733D01*
G01X665014Y68145D02*
X666177Y69440D01*
G01X665483Y66886D02*
G03X665981Y67276I-861J1612D01*
G01X664870Y68034D02*
G03X665014Y68145I-245J466D01*
G01X665199Y66734D02*
X665483Y66886D01*
G01X664585Y67880D02*
X664870Y68033D01*
G01X671090Y57651D02*
X672785Y58625D01*
G01X668745Y57805D02*
X672265Y59826D01*
G01X670471Y57296D02*
X671090Y57651D01*
G01X668745Y57805D02*
X672265Y59826D01*
G01X669393Y56677D02*
X670471Y57296D01*
G01X668745Y57805D02*
X672265Y59826D01*
G01X668740Y57802D02*
X668745Y57805D01*
G01X668496Y57662D02*
X668740Y57802D01*
G01X666564Y52844D02*
X669381Y56671D01*
G01X665515Y53615D02*
X668495Y57663D01*
G01X665464Y53544D02*
X665512Y53609D01*
G01X647036Y69150D02*
X642513Y62689D01*
G01X648267Y68640D02*
X643447Y61755D01*
G01X650174Y86944D02*
X647036Y69150D01*
G01X651405Y86434D02*
X648267Y68640D01*
G01X643150Y71612D02*
X648009Y99168D01*
G01X644381Y71102D02*
X649240Y98658D01*
G01X639714Y66706D02*
X643150Y71612D01*
G01X640779Y65960D02*
X644381Y71102D01*
G01X640684Y65824D02*
X640779Y65959D01*
G01X648267Y68640D02*
X643447Y61755D01*
G01X647036Y69150D02*
X642513Y62689D01*
G01X651405Y86434D02*
X648267Y68640D01*
G01X650174Y86944D02*
X647036Y69150D01*
G01X644381Y71102D02*
X649240Y98658D01*
G01X643150Y71612D02*
X648009Y99168D01*
G01X640779Y65960D02*
X644381Y71102D01*
G01X639714Y66706D02*
X643150Y71612D01*
G01X640684Y65824D02*
X640779Y65959D01*
G01X639714Y66706D02*
X643150Y71612D01*
G01X651271Y88511D02*
X650174Y86944D01*
G01X652205Y87577D02*
X651405Y86434D01*
G01X653191Y89855D02*
X651271Y88511D01*
G01X653701Y88624D02*
X652205Y87577D01*
G01X656393Y90419D02*
X653191Y89855D01*
G01X656400Y89100D02*
X653701Y88624D01*
G01X666435Y88763D02*
X656393Y90419D01*
G01X666442Y87444D02*
X656400Y89100D01*
G01X679734Y91108D02*
X666435Y88763D01*
G01X680238Y89876D02*
X666442Y87444D01*
G01X643989Y99583D02*
X650715Y109189D01*
G01X645220Y99073D02*
X651649Y108255D01*
G01X640216Y78163D02*
X643989Y99583D01*
G01X641426Y77533D02*
X645220Y99073D01*
G01X640195Y107081D02*
X667037Y124977D01*
G01X641120Y106135D02*
X667532Y123743D01*
G01X638660Y104890D02*
X640195Y107081D01*
G01X639864Y104342D02*
X641120Y106135D01*
G01X637920Y96497D02*
X639864Y104342D01*
G01X639734Y87336D02*
X637920Y96497D01*
G01X638455Y80604D02*
X639734Y87336D01*
G01X653456Y106946D02*
X668808Y117697D01*
G01X654390Y106012D02*
X669318Y116466D01*
G01X648009Y99168D02*
X653456Y106946D01*
G01X649240Y98658D02*
X654390Y106012D01*
G01X652205Y87577D02*
X651405Y86434D01*
G01X651271Y88511D02*
X650174Y86944D01*
G01X653701Y88624D02*
X652205Y87577D01*
G01X653191Y89855D02*
X651271Y88511D01*
G01X656400Y89100D02*
X653701Y88624D01*
G01X656393Y90419D02*
X653191Y89855D01*
G01X666442Y87444D02*
X656400Y89100D01*
G01X666435Y88763D02*
X656393Y90419D01*
G01X680238Y89876D02*
X666442Y87444D01*
G01X679734Y91108D02*
X666435Y88763D01*
G01X645220Y99073D02*
X651649Y108255D01*
G01X643989Y99583D02*
X650715Y109189D01*
G01X641426Y77533D02*
X645220Y99073D01*
G01X640216Y78163D02*
X643989Y99583D01*
G01X641120Y106135D02*
X667532Y123743D01*
G01X640195Y107081D02*
X667037Y124977D01*
G01X639864Y104342D02*
X641120Y106135D01*
G01X638660Y104890D02*
X640195Y107081D01*
G01X637920Y96497D02*
X639864Y104342D01*
G01X639734Y87336D02*
X637920Y96497D01*
G01X638455Y80604D02*
X639734Y87336D01*
G01X654390Y106012D02*
X669318Y116466D01*
G01X653456Y106946D02*
X668808Y117697D01*
G01X649240Y98658D02*
X654390Y106012D01*
G01X648009Y99168D02*
X653456Y106946D01*
G01X668106Y121365D02*
X706000Y128047D01*
G01X668616Y120134D02*
X706000Y126726D01*
G01X650715Y109189D02*
X668106Y121365D01*
G01X651649Y108255D02*
X668616Y120134D01*
G01X667037Y124977D02*
X693060Y129565D01*
G01X667532Y123743D02*
X693300Y128287D01*
G01X668808Y117697D02*
X705437Y124156D01*
G01X669318Y116466D02*
X705437Y122835D01*
G01X668616Y120134D02*
X706000Y126726D01*
G01X668106Y121365D02*
X706000Y128047D01*
G01X651649Y108255D02*
X668616Y120134D01*
G01X650715Y109189D02*
X668106Y121365D01*
G01X667532Y123743D02*
X693300Y128287D01*
G01X667037Y124977D02*
X693060Y129565D01*
G01X669318Y116466D02*
X705437Y122835D01*
G01X668808Y117697D02*
X705437Y124156D01*
G01X664814Y127181D02*
X692916Y132137D01*
G01X664327Y128416D02*
X692676Y133415D01*
G01X651813Y118739D02*
X664814Y127181D01*
G01X651307Y119961D02*
X664327Y128416D01*
G01X662458Y135941D02*
X692676Y141268D01*
G01X662945Y134706D02*
X692916Y139990D01*
G01X647641Y126319D02*
X662458Y135941D01*
G01X648147Y125097D02*
X662945Y134706D01*
G01X660019Y138624D02*
X705506Y147725D01*
G01Y146399D02*
X660011Y137296D01*
G01X654554Y139786D02*
X660019Y138624D01*
G01X660011Y137296D02*
X654048Y138564D01*
G01X651521Y141755D02*
X654554Y139786D01*
G01X654048Y138564D02*
X650581Y140815D01*
G01X650836Y142811D02*
X651521Y141756D01*
G01X650581Y140815D02*
X648929Y143358D01*
G01X650581Y140815D02*
X648929Y143358D01*
G01X664327Y128416D02*
X692676Y133415D01*
G01X664814Y127181D02*
X692916Y132137D01*
G01X651307Y119961D02*
X664327Y128416D01*
G01X651813Y118739D02*
X664814Y127181D01*
G01X662945Y134706D02*
X692916Y139990D01*
G01X662458Y135941D02*
X692676Y141268D01*
G01X648147Y125097D02*
X662945Y134706D01*
G01X647641Y126319D02*
X662458Y135941D01*
G01X650581Y140815D02*
X648929Y143358D01*
G01X650836Y142811D02*
X651521Y141756D01*
G01X654048Y138564D02*
X650581Y140815D01*
G01X651521Y141755D02*
X654554Y139786D01*
G01X660011Y137296D02*
X654048Y138564D01*
G01X654554Y139786D02*
X660019Y138624D01*
G01X705506Y146399D02*
X660011Y137296D01*
G01X660019Y138624D02*
X705506Y147725D01*
G01X664467Y131047D02*
X692916Y136064D01*
G01X663980Y132282D02*
X692676Y137342D01*
G01X650932Y122259D02*
X664467Y131047D01*
G01X650426Y123481D02*
X663980Y132282D01*
G01D02*
X692676Y137342D01*
G01X664467Y131047D02*
X692916Y136064D01*
G01X650426Y123481D02*
X663980Y132282D01*
G01X650932Y122259D02*
X664467Y131047D01*
G01X650151Y143865D02*
X650836Y142811D01*
G01X648765Y150384D02*
X650151Y143865D01*
G01X648929Y143358D02*
X647543Y149878D01*
G01X645889Y154812D02*
X648765Y150384D01*
G01X647543Y149878D02*
X644949Y153872D01*
G01X644085Y155984D02*
X645889Y154812D01*
G01X644949Y153872D02*
X643579Y154762D01*
G01X638723Y157124D02*
X644085Y155984D01*
G01X643579Y154762D02*
X638723Y155794D01*
G01X643579Y154762D02*
X638723Y155794D01*
G01Y157124D02*
X644085Y155984D01*
G01X644949Y153872D02*
X643579Y154762D01*
G01X644085Y155984D02*
X645889Y154812D01*
G01X647543Y149878D02*
X644949Y153872D01*
G01X645889Y154812D02*
X648765Y150384D01*
G01X648929Y143358D02*
X647543Y149878D01*
G01X648765Y150384D02*
X650151Y143865D01*
G01D02*
X650836Y142811D01*
G01X717922Y147846D02*
X650006Y162164D01*
G01X717929Y149174D02*
X650005Y163493D01*
G01X717916Y157023D02*
X648146Y170976D01*
G01X717916Y155697D02*
X648147Y169650D01*
G01X717929Y149174D02*
X650005Y163493D01*
G01X717922Y147846D02*
X650006Y162164D01*
G01X717916Y155697D02*
X648147Y169650D01*
G01X717916Y157023D02*
X648146Y170976D01*
G01X717916Y160950D02*
X648660Y174799D01*
G01X717916Y159624D02*
X648665Y173472D01*
G01X717916Y159624D02*
X648665Y173472D01*
G01X648125Y165726D02*
X717916Y151770D01*
G01X648117Y167054D02*
X717916Y153096D01*
G01Y159624D02*
X648665Y173472D01*
G01X717916Y160950D02*
X648660Y174799D01*
G01X648117Y167054D02*
X717916Y153096D01*
G01X648125Y165726D02*
X717916Y151770D01*
G01X647974Y179832D02*
X717894Y164976D01*
G01X717891Y163647D02*
X647973Y178502D01*
G01X717891Y163647D02*
X647973Y178502D01*
G01X647974Y179832D02*
X717894Y164976D01*
G01X714508Y170546D02*
X645984Y185114D01*
G01X645985Y186444D02*
X714508Y171876D01*
G01X645985Y186444D02*
X714508Y171876D01*
G01Y170546D02*
X645984Y185114D01*
G01X644530Y406063D02*
X677487Y400252D01*
G01X644530Y404742D02*
X676977Y399021D01*
G01X644530Y404742D02*
X676977Y399021D01*
G01X644530Y406063D02*
X677487Y400252D01*
G01X678647Y409852D02*
X645548Y415687D01*
G01X678647Y409852D02*
X645548Y415687D01*
G01X678647Y409852D02*
X645548Y415687D01*
G01X678647Y409852D02*
X645548Y415687D01*
G01X678647Y409852D02*
X645548Y415687D01*
G01X646136Y409884D02*
X676082Y404605D01*
G01X651295Y410295D02*
X646136Y411205D01*
G01X655924Y409479D02*
X654299Y409766D01*
G01X660552Y408664D02*
X658927Y408950D01*
G01X665181Y407848D02*
X663556Y408134D01*
G01X676592Y405836D02*
X668185Y407318D01*
G01X651295Y410295D02*
X646136Y411205D01*
G01Y409884D02*
X676082Y404605D01*
G01X655924Y409479D02*
X654299Y409766D01*
G01X646136Y409884D02*
X676082Y404605D01*
G01X660552Y408664D02*
X658927Y408950D01*
G01X646136Y409884D02*
X676082Y404605D01*
G01X665181Y407848D02*
X663556Y408134D01*
G01X646136Y409884D02*
X676082Y404605D01*
G01X676592Y405836D02*
X668185Y407318D01*
G01X646136Y409884D02*
X676082Y404605D01*
G01X670598Y412592D02*
X679157Y411083D01*
G01X662323Y414051D02*
X670598Y412592D01*
G01X656627Y415055D02*
X662323Y414051D01*
G01X645548Y417008D02*
X656627Y415055D01*
G01X670598Y412592D02*
X679157Y411083D01*
G01X662323Y414051D02*
X670598Y412592D01*
G01X656627Y415055D02*
X662323Y414051D01*
G01X645548Y417008D02*
X656627Y415055D01*
G01X807427Y307228D02*
X639215Y547461D01*
G01X808658Y307738D02*
X640149Y548395D01*
G01X804721Y301404D02*
X644683Y529963D01*
G01X803490Y300894D02*
X643749Y529029D01*
G01X808658Y307738D02*
X640149Y548395D01*
G01X807427Y307228D02*
X639215Y547461D01*
G01X803490Y300894D02*
X643749Y529029D01*
G01X804721Y301404D02*
X644683Y529963D01*
G01X832369Y299190D02*
X650693Y558661D01*
G01X651627Y559595D02*
X833600Y299700D01*
G01X836282Y308433D02*
X661829Y557577D01*
G01X651627Y559595D02*
X833600Y299700D01*
G01X832369Y299190D02*
X650693Y558661D01*
G01X836282Y308433D02*
X661829Y557577D01*
G01X825923Y300188D02*
X654916Y544408D01*
G01X824692Y299678D02*
X653982Y543474D01*
G01X824692Y299678D02*
X653982Y543474D01*
G01X825923Y300188D02*
X654916Y544408D01*
G01X669840Y567759D02*
X841755Y322240D01*
G01X670774Y568693D02*
X842986Y322750D01*
G01X670774Y568693D02*
X842986Y322750D01*
G01X669840Y567759D02*
X841755Y322240D01*
G01X665110Y560075D02*
X839853Y310520D01*
G01X666044Y561009D02*
X841084Y311030D01*
G01X666044Y561009D02*
X841084Y311030D01*
G01X665110Y560075D02*
X839853Y310520D01*
G01X837513Y308943D02*
X662763Y558511D01*
G01X837513Y308943D02*
X662763Y558511D01*
G01X656736Y759059D02*
X915192Y389945D01*
G01X655505Y758549D02*
X913961Y389435D01*
G01X655505Y758549D02*
X913961Y389435D01*
G01X656736Y759059D02*
X915192Y389945D01*
G01X661566Y731279D02*
X907574Y379942D01*
G01X662500Y732213D02*
X908805Y380452D01*
G01X662500Y732213D02*
X908805Y380452D01*
G01X661566Y731279D02*
X907574Y379942D01*
G01X653624Y801271D02*
X911758Y432616D01*
G01X652393Y800761D02*
X910527Y432106D01*
G01X652393Y800761D02*
X910527Y432106D01*
G01X653624Y801271D02*
X911758Y432616D01*
G01X650911Y792093D02*
X656736Y759059D01*
G01X649680Y791583D02*
X655505Y758549D01*
G01X649680Y791583D02*
X655505Y758549D01*
G01X650911Y792093D02*
X656736Y759059D01*
G01X669195Y789220D02*
X913596Y440182D01*
G01X670426Y789730D02*
X914827Y440692D01*
G01X662577Y826750D02*
X669195Y789220D01*
G01X663898Y826750D02*
X670426Y789730D01*
G01X647236Y837496D02*
X653624Y801271D01*
G01X646005Y836986D02*
X652393Y800761D01*
G01X670426Y789730D02*
X914827Y440692D01*
G01X669195Y789220D02*
X913596Y440182D01*
G01X663898Y826750D02*
X670426Y789730D01*
G01X662577Y826750D02*
X669195Y789220D01*
G01X646005Y836986D02*
X652393Y800761D01*
G01X647236Y837496D02*
X653624Y801271D01*
G01X674615Y843398D02*
X668905Y851553D01*
G01X674615Y843398D02*
X668905Y851553D01*
G01X663679Y833000D02*
X662577Y826750D01*
G01X665000Y833000D02*
X663898Y826750D01*
G01X661823Y843528D02*
X663679Y833000D01*
G01X663054Y844038D02*
X665000Y833000D01*
G01X657101Y850271D02*
X661823Y843528D01*
G01X658035Y851205D02*
X663054Y844038D01*
G01X647174Y857223D02*
X657101Y850271D01*
G01X665000Y833000D02*
X663898Y826750D01*
G01X663679Y833000D02*
X662577Y826750D01*
G01X663054Y844038D02*
X665000Y833000D01*
G01X661823Y843528D02*
X663679Y833000D01*
G01X658035Y851205D02*
X663054Y844038D01*
G01X657101Y850271D02*
X661823Y843528D01*
G01X647174Y857223D02*
X657101Y850271D01*
G01X662736Y867753D02*
Y872882D01*
G01X664036Y868163D02*
Y872882D01*
G01X666406Y862510D02*
X662736Y867753D01*
G01X667340Y863444D02*
X664036Y868163D01*
G01X682236Y851426D02*
X666406Y862510D01*
G01X683170Y852360D02*
X667340Y863444D01*
G01X651438Y868343D02*
Y872882D01*
G01X650138Y867932D02*
Y872882D01*
G01X655520Y862513D02*
X651438Y868343D01*
G01X654586Y861579D02*
X650138Y867932D01*
G01X669839Y852487D02*
X655520Y862513D01*
G01X668905Y851553D02*
X654586Y861579D01*
G01X675846Y843908D02*
X669839Y852487D01*
G01X664036Y868163D02*
Y872882D01*
G01X662736Y867753D02*
Y872882D01*
G01X667340Y863444D02*
X664036Y868163D01*
G01X666406Y862510D02*
X662736Y867753D01*
G01X683170Y852360D02*
X667340Y863444D01*
G01X682236Y851426D02*
X666406Y862510D01*
G01X650138Y867932D02*
Y872882D01*
G01X651438Y868343D02*
Y872882D01*
G01X654586Y861579D02*
X650138Y867932D01*
G01X655520Y862513D02*
X651438Y868343D01*
G01X668905Y851553D02*
X654586Y861579D01*
G01X669839Y852487D02*
X655520Y862513D01*
G01X675846Y843908D02*
X669839Y852487D01*
G01X647920Y858288D02*
X658035Y851205D01*
G01X646137Y857949D02*
X647174Y857223D01*
G01X646647Y859180D02*
X647920Y858288D01*
G01D02*
X658035Y851205D01*
G01X646647Y859180D02*
X647920Y858288D01*
G01X646137Y857949D02*
X647174Y857223D01*
G01X695852Y61786D02*
X715582Y58310D01*
G01X695943Y60449D02*
X715582Y56989D01*
G01X676076Y55455D02*
X695852Y61786D01*
G01X676773Y54312D02*
X695943Y60449D01*
G01X674472Y53851D02*
X676076Y55455D01*
G01X675536Y53075D02*
X676773Y54312D01*
G01X688754Y73361D02*
X712216Y68378D01*
G01X688754Y72031D02*
X712193Y67053D01*
G01X676289Y70712D02*
X688754Y73361D01*
G01X676611Y69451D02*
X688754Y72031D01*
G01X676288Y70712D02*
X676289D01*
G01X676611Y69451D02*
X688754Y72031D01*
G01X676280Y70710D02*
X676288Y70712D01*
G01X676611Y69451D02*
X688754Y72031D01*
G01X676195Y70683D02*
G02X676280Y70710I801J-2373D01*
G01X676069Y69093D02*
G02X676601Y69448I910J-787D01*
G01X675087Y69947D02*
G02X676195Y70683I1890J-1643D01*
G01X676069Y69093D02*
G02X676601Y69448I910J-787D01*
G01X674658Y69403D02*
G02X675087Y69947I5760J-4101D01*
G01X675718Y68648D02*
G02X676069Y69093I4700J-3346D01*
G01X675641Y68537D02*
G02X675718Y68648I4779J-3233D01*
G01X674563Y69266D02*
G02X674658Y69403I5858J-3960D01*
G01X675718Y68648D02*
G02X676069Y69093I4700J-3346D01*
G01X674742Y64292D02*
G02X675641Y68537I5680J1015D01*
G01X695943Y60449D02*
X715582Y56989D01*
G01X695852Y61786D02*
X715582Y58310D01*
G01X676773Y54312D02*
X695943Y60449D01*
G01X676076Y55455D02*
X695852Y61786D01*
G01X675536Y53075D02*
X676773Y54312D01*
G01X674472Y53851D02*
X676076Y55455D01*
G01X688754Y72031D02*
X712193Y67053D01*
G01X688754Y73361D02*
X712216Y68378D01*
G01X676611Y69451D02*
X688754Y72031D01*
G01X676289Y70712D02*
X688754Y73361D01*
G01X676288Y70712D02*
X676289D01*
G01X676280Y70710D02*
X676288Y70712D01*
G01X676069Y69093D02*
G02X676601Y69448I910J-787D01*
G01X676195Y70683D02*
G02X676280Y70710I801J-2373D01*
G01X675087Y69947D02*
G02X676195Y70683I1890J-1643D01*
G01X675718Y68648D02*
G02X676069Y69093I4700J-3346D01*
G01X674658Y69403D02*
G02X675087Y69947I5760J-4101D01*
G01X674563Y69266D02*
G02X674658Y69403I5858J-3960D01*
G01X675641Y68537D02*
G02X675718Y68648I4779J-3233D01*
G01X674658Y69403D02*
G02X675087Y69947I5760J-4101D01*
G01X674742Y64292D02*
G02X675641Y68537I5680J1015D01*
G01X674563Y69266D02*
G02X674658Y69403I5858J-3960D01*
G01X697785Y66327D02*
X713184Y63052D01*
G01X697785Y64997D02*
X713161Y61727D01*
G01X683936Y63379D02*
X697785Y66327D01*
G01X684261Y62119D02*
X697785Y64997D01*
G01X672265Y59826D02*
X683936Y63379D01*
G01X672785Y58625D02*
X684261Y62119D01*
G01X697785Y64997D02*
X713161Y61727D01*
G01X697785Y66327D02*
X713184Y63052D01*
G01X684261Y62119D02*
X697785Y64997D01*
G01X683936Y63379D02*
X697785Y66327D01*
G01X672785Y58625D02*
X684261Y62119D01*
G01X672265Y59826D02*
X683936Y63379D01*
G01X683923Y80444D02*
X717727Y73259D01*
G01X683923Y79114D02*
X717727Y71929D01*
G01X681829Y79999D02*
X683923Y80444D01*
G01X682077Y78722D02*
X683923Y79114D01*
G01X682060Y78719D02*
X682077Y78722D01*
G01X682055Y78718D02*
X682060Y78719D01*
G01X682054Y78718D02*
X682055D01*
G01X681544Y79949D02*
X681829Y79999D01*
G01X682077Y78722D02*
X683923Y79114D01*
G01X676914Y76706D02*
X681544Y79949D01*
G01X682060Y78719D02*
X682077Y78722D01*
G01X682054Y78718D02*
X682055D01*
G01X677436Y75484D02*
X682054Y78718D01*
G01X671249Y75581D02*
X676914Y76706D01*
G01X671779Y74360D02*
X677436Y75484D01*
G01X683923Y79114D02*
X717727Y71929D01*
G01X683923Y80444D02*
X717727Y73259D01*
G01X682077Y78722D02*
X683923Y79114D01*
G01X681829Y79999D02*
X683923Y80444D01*
G01X681544Y79949D02*
X681829Y79999D01*
G01X682060Y78719D02*
X682077Y78722D01*
G01X681829Y79999D02*
X683923Y80444D01*
G01X676914Y76706D02*
X681544Y79949D01*
G01X682055Y78718D02*
X682060Y78719D01*
G01X681829Y79999D02*
X683923Y80444D01*
G01X682054Y78718D02*
X682055D01*
G01X681829Y79999D02*
X683923Y80444D01*
G01X676914Y76706D02*
X681544Y79949D01*
G01X677436Y75484D02*
X682054Y78718D01*
G01X676914Y76706D02*
X681544Y79949D01*
G01X671779Y74360D02*
X677436Y75484D01*
G01X671249Y75581D02*
X676914Y76706D01*
G01X705695Y108924D02*
X679734Y91108D01*
G01X706218Y107706D02*
X680238Y89876D01*
G01X706218Y107706D02*
X680238Y89876D01*
G01X705695Y108924D02*
X679734Y91108D01*
G01X696980Y130348D02*
X705945Y131929D01*
G01X697220Y129070D02*
X705930Y130606D01*
G01X693060Y129565D02*
X696980Y130348D01*
G01X693300Y128287D02*
X697220Y129070D01*
G01D02*
X705930Y130606D01*
G01X696980Y130348D02*
X705945Y131929D01*
G01X693300Y128287D02*
X697220Y129070D01*
G01X693060Y129565D02*
X696980Y130348D01*
G01X692916Y132137D02*
X705416Y134637D01*
G01X692676Y133415D02*
X705416Y135963D01*
G01X692676Y141268D02*
X705416Y143816D01*
G01X692916Y139990D02*
X705416Y142490D01*
G01X692676Y133415D02*
X705416Y135963D01*
G01X692916Y132137D02*
X705416Y134637D01*
G01X692916Y139990D02*
X705416Y142490D01*
G01X692676Y141268D02*
X705416Y143816D01*
G01X692916Y136064D02*
X705416Y138564D01*
G01X692676Y137342D02*
X705416Y139890D01*
G01X692676Y137342D02*
X705416Y139890D01*
G01X692916Y136064D02*
X705416Y138564D01*
G01X711820Y348955D02*
X698551Y358246D01*
G01X686030Y368601D02*
X712566Y350020D01*
G01X698551Y358246D02*
X685096Y367667D01*
G01X711820Y348955D02*
X698551Y358246D01*
G01X682500Y373643D02*
X686030Y368601D01*
G01X685096Y367667D02*
X681200Y373233D01*
G01X682500Y377618D02*
Y373643D01*
G01X681200Y373233D02*
Y377618D01*
G01Y373233D02*
Y377618D01*
G01X682500D02*
Y373643D01*
G01X685096Y367667D02*
X681200Y373233D01*
G01X682500Y373643D02*
X686030Y368601D01*
G01X698551Y358246D02*
X685096Y367667D01*
G01X686030Y368601D02*
X712566Y350020D01*
G01X711820Y348955D02*
X698551Y358246D01*
G01X686030Y368601D02*
X712566Y350020D01*
G01X686728Y393781D02*
X753953Y297771D01*
G01X685794Y392847D02*
X752722Y297261D01*
G01X685794Y392847D02*
X752722Y297261D01*
G01X686728Y393781D02*
X753953Y297771D01*
G01X689076Y395507D02*
X756587Y298990D01*
G01X757818Y299500D02*
X690010Y396441D01*
G01X757818Y299500D02*
X690010Y396441D01*
G01X689076Y395507D02*
X756587Y298990D01*
G01X683647Y419909D02*
X765550Y302938D01*
G01X764319Y302428D02*
X682713Y418975D01*
G01X764319Y302428D02*
X682713Y418975D01*
G01X683647Y419909D02*
X765550Y302938D01*
G01X684661Y425296D02*
X769487Y304186D01*
G01X683727Y424362D02*
X768256Y303676D01*
G01X683727Y424362D02*
X768256Y303676D01*
G01X684661Y425296D02*
X769487Y304186D01*
G01X677487Y400252D02*
X686728Y393781D01*
G01X676977Y399021D02*
X685794Y392847D01*
G01X676977Y399021D02*
X685794Y392847D01*
G01X677487Y400252D02*
X686728Y393781D01*
G01X690313Y403270D02*
X761694Y301396D01*
G01X760463Y300886D02*
X689379Y402336D01*
G01X679157Y411083D02*
X690313Y403270D01*
G01X689379Y402336D02*
X678647Y409852D01*
G01X689379Y402336D02*
X678647Y409852D01*
G01X679157Y411083D02*
X690313Y403270D01*
G01X760463Y300886D02*
X689379Y402336D01*
G01X690313Y403270D02*
X761694Y301396D01*
G01X676082Y404605D02*
X689076Y395507D01*
G01X690010Y396441D02*
X676592Y405836D01*
G01X690010Y396441D02*
X676592Y405836D01*
G01X676082Y404605D02*
X689076Y395507D01*
G01X858632Y324249D02*
X679480Y580108D01*
G01X857401Y323739D02*
X678546Y579174D01*
G01X857401Y323739D02*
X678546Y579174D01*
G01X858632Y324249D02*
X679480Y580108D01*
G01X679132Y572643D02*
X851306Y326772D01*
G01X680066Y573576D02*
X852537Y327282D01*
G01X680066Y573576D02*
X852537Y327282D01*
G01X679132Y572643D02*
X851306Y326772D01*
G01X672787Y571957D02*
X846569Y323780D01*
G01X673721Y572891D02*
X847800Y324290D01*
G01X673721Y572891D02*
X847800Y324290D01*
G01X672787Y571957D02*
X846569Y323780D01*
G01X694087Y585043D02*
X869302Y334806D01*
G01X870537Y335309D02*
X695021Y585977D01*
G01X692144Y595304D02*
X874776Y334485D01*
G01X693078Y596238D02*
X876007Y334995D01*
G01X870537Y335309D02*
X695021Y585977D01*
G01X694087Y585043D02*
X869302Y334806D01*
G01X693078Y596238D02*
X876007Y334995D01*
G01X692144Y595304D02*
X874776Y334485D01*
G01X688209Y584991D02*
X867162Y329419D01*
G01X865931Y328909D02*
X687275Y584057D01*
G01X865931Y328909D02*
X687275Y584057D01*
G01X688209Y584991D02*
X867162Y329419D01*
G01X678865Y585698D02*
X862006Y324149D01*
G01X679799Y586632D02*
X863237Y324659D01*
G01X679799Y586632D02*
X863237Y324659D01*
G01X678865Y585698D02*
X862006Y324149D01*
G01X695411Y600868D02*
X878333Y339624D01*
G01X696345Y601802D02*
X879564Y340134D01*
G01X702239Y602688D02*
X882226Y345628D01*
G01X703173Y603622D02*
X883457Y346138D01*
G01X696345Y601802D02*
X879564Y340134D01*
G01X695411Y600868D02*
X878333Y339624D01*
G01X703173Y603622D02*
X883457Y346138D01*
G01X702239Y602688D02*
X882226Y345628D01*
G01X919397Y441619D02*
X696502Y759945D01*
G01X918166Y441109D02*
X695271Y759435D01*
G01X918166Y441109D02*
X695271Y759435D01*
G01X919397Y441619D02*
X696502Y759945D01*
G01D02*
X687500Y811000D01*
G01X695271Y759435D02*
X686269Y810490D01*
G01X695271Y759435D02*
X686269Y810490D01*
G01X696502Y759945D02*
X687500Y811000D01*
G01X723769Y774990D02*
X687900Y826217D01*
G01X725000Y775500D02*
X689200Y826627D01*
G01X687500Y811000D02*
X676500Y826710D01*
G01X686269Y810490D02*
X675200Y826300D01*
G01X725000Y775500D02*
X689200Y826627D01*
G01X723769Y774990D02*
X687900Y826217D01*
G01X686269Y810490D02*
X675200Y826300D01*
G01X687500Y811000D02*
X676500Y826710D01*
G01X706049Y831184D02*
X691103Y852528D01*
G01X706983Y832118D02*
X692037Y853462D01*
G01X710926Y832792D02*
X687933Y865632D01*
G01X711860Y833726D02*
X689233Y866043D01*
G01X706983Y832118D02*
X692037Y853462D01*
G01X706049Y831184D02*
X691103Y852528D01*
G01X706049Y831184D02*
X691103Y852528D01*
G01X711860Y833726D02*
X689233Y866043D01*
G01X710926Y832792D02*
X687933Y865632D01*
G01X710926Y832792D02*
X687933Y865632D01*
G01X687204Y844331D02*
X682236Y851426D01*
G01X688435Y844841D02*
X683170Y852360D01*
G01X687900Y840386D02*
X687204Y844331D01*
G01X689200Y840500D02*
X688435Y844841D01*
G01X687900Y826217D02*
Y840386D01*
G01X689200Y826627D02*
Y840500D01*
G01X676500Y840200D02*
X675846Y843908D01*
G01X675200Y840086D02*
X674615Y843398D01*
G01X676500Y826710D02*
Y840200D01*
G01X675200Y826300D02*
Y840086D01*
G01X688435Y844841D02*
X683170Y852360D01*
G01X687204Y844331D02*
X682236Y851426D01*
G01X689200Y840500D02*
X688435Y844841D01*
G01X687900Y840386D02*
X687204Y844331D01*
G01X689200Y826627D02*
Y840500D01*
G01X687900Y826217D02*
Y840386D01*
G01X675200Y840086D02*
X674615Y843398D01*
G01X676500Y840200D02*
X675846Y843908D01*
G01X675200Y826300D02*
Y840086D01*
G01X676500Y826710D02*
Y840200D01*
G01X700150Y860235D02*
Y866174D01*
G01X701450Y860646D02*
Y866506D01*
G01X702352Y857090D02*
X700150Y860235D01*
G01X703286Y858024D02*
X701450Y860646D01*
G01X705672Y854765D02*
X702352Y857090D01*
G01X706182Y855996D02*
X703286Y858024D01*
G01X701450Y860646D02*
Y866506D01*
G01X700150Y860235D02*
Y866174D01*
G01X703286Y858024D02*
X701450Y860646D01*
G01X702352Y857090D02*
X700150Y860235D01*
G01X706182Y855996D02*
X703286Y858024D01*
G01X705672Y854765D02*
X702352Y857090D01*
G01X675335Y866111D02*
Y872882D01*
G01X676635Y866522D02*
Y872882D01*
G01X678827Y861124D02*
X675335Y866111D01*
G01X679761Y862058D02*
X676635Y866522D01*
G01X691103Y852528D02*
X678827Y861124D01*
G01X692037Y853462D02*
X679761Y862058D01*
G01X687933Y865632D02*
Y872882D01*
G01X689233Y866043D02*
Y872882D01*
G01X676635Y866522D02*
Y872882D01*
G01X675335Y866111D02*
Y872882D01*
G01X679761Y862058D02*
X676635Y866522D01*
G01X678827Y861124D02*
X675335Y866111D01*
G01X692037Y853462D02*
X679761Y862058D01*
G01X691103Y852528D02*
X678827Y861124D01*
G01X689233Y866043D02*
Y872882D01*
G01X687933Y865632D02*
Y872882D01*
G01X727128Y37300D02*
X744014D01*
G01X735592Y38600D02*
X737242D01*
G01X727127D02*
X732542D01*
G01X726738Y37138D02*
G02X727128Y37300I391J-390D01*
G01X725818Y38057D02*
G02X727127Y38600I1310J-1309D01*
G01X725367Y35767D02*
X726738Y37138D01*
G01X724448Y36687D02*
X725818Y38057D01*
G01X725205Y35377D02*
G02X725367Y35767I552J-1D01*
G01X723905Y35378D02*
G02X724448Y36687I1852J-1D01*
G01X725205Y34045D02*
Y35377D01*
G01X723905Y34045D02*
Y35378D01*
G01X727128Y37300D02*
X744014D01*
G01X735592Y38600D02*
X737242D01*
G01X727128Y37300D02*
X744014D01*
G01X727127Y38600D02*
X732542D01*
G01X727128Y37300D02*
X744014D01*
G01X725818Y38057D02*
G02X727127Y38600I1310J-1309D01*
G01X726738Y37138D02*
G02X727128Y37300I391J-390D01*
G01X724448Y36687D02*
X725818Y38057D01*
G01X725367Y35767D02*
X726738Y37138D01*
G01X723905Y35378D02*
G02X724448Y36687I1852J-1D01*
G01X725205Y35377D02*
G02X725367Y35767I552J-1D01*
G01X723905Y34045D02*
Y35378D01*
G01X725205Y34045D02*
Y35377D01*
G01X727559Y47001D02*
X746882D01*
G01X736959Y48301D02*
X738609D01*
G01X732259D02*
X733909D01*
G01X727559D02*
X729209D01*
G01X727559Y47001D02*
X746882D01*
G01X736959Y48301D02*
X738609D01*
G01X727559Y47001D02*
X746882D01*
G01X732259Y48301D02*
X733909D01*
G01X727559Y47001D02*
X746882D01*
G01X727559Y48301D02*
X729209D01*
G01X727559Y47001D02*
X746882D01*
G01X715582Y58310D02*
X739753Y62572D01*
G01X715582Y56989D02*
X740263Y61341D01*
G01X727119Y71002D02*
X772932Y103084D01*
G01X727629Y69771D02*
X773461Y101867D01*
G01X712216Y68378D02*
X727119Y71002D01*
G01X712193Y67053D02*
X727629Y69771D01*
G01X715582Y56989D02*
X740263Y61341D01*
G01X715582Y58310D02*
X739753Y62572D01*
G01X727629Y69771D02*
X773461Y101867D01*
G01X727119Y71002D02*
X772932Y103084D01*
G01X712193Y67053D02*
X727629Y69771D01*
G01X712216Y68378D02*
X727119Y71002D01*
G01X726500Y73794D02*
X728006Y74773D01*
G01X717727Y73259D02*
X725992Y75016D01*
G01X717727Y71929D02*
X726500Y73794D01*
G01X727766Y65622D02*
X769246Y94678D01*
G01X728276Y64391D02*
X769775Y93461D01*
G01X713184Y63052D02*
X727766Y65622D01*
G01X713161Y61727D02*
X728276Y64391D01*
G01X726500Y73794D02*
X728006Y74773D01*
G01X717727Y71929D02*
X726500Y73794D01*
G01X717727Y73259D02*
X725992Y75016D01*
G01X728276Y64391D02*
X769775Y93461D01*
G01X727766Y65622D02*
X769246Y94678D01*
G01X713161Y61727D02*
X728276Y64391D01*
G01X713184Y63052D02*
X727766Y65622D01*
G01X727066Y75713D02*
X742305Y99180D01*
G01X728006Y74773D02*
X743258Y98260D01*
G01X725992Y75016D02*
X727066Y75713D01*
G01X728006Y74773D02*
X743258Y98260D01*
G01X727066Y75713D02*
X742305Y99180D01*
G01X725992Y75016D02*
X727066Y75713D01*
G01X714318Y109427D02*
X706218Y107706D01*
G01X714318Y109427D02*
X706218Y107706D01*
G01X714318Y110757D02*
X705695Y108924D01*
G01X718587Y109849D02*
X714318Y110757D01*
G01X718564Y108524D02*
X714318Y109427D01*
G01X731192Y112072D02*
X718587Y109849D01*
G01X731702Y110841D02*
X718564Y108524D01*
G01X733044Y113368D02*
X731192Y112072D01*
G01X733554Y112137D02*
X731702Y110841D01*
G01X758063Y117780D02*
X733044Y113368D01*
G01X758063Y116459D02*
X733554Y112137D01*
G01X722748Y126183D02*
X739696Y122580D01*
G01X722748Y124853D02*
X739696Y121250D01*
G01X719948Y125587D02*
X722748Y126183D01*
G01X719971Y124262D02*
X722748Y124853D01*
G01X706000Y128047D02*
X719948Y125587D01*
G01X706000Y126726D02*
X719971Y124262D01*
G01X721964Y129935D02*
X739409Y126228D01*
G01X721957Y128607D02*
X739409Y124898D01*
G01X718955Y129328D02*
X721964Y129935D01*
G01X718956Y128002D02*
X721957Y128607D01*
G01X705945Y131929D02*
X718955Y129328D01*
G01X705930Y130606D02*
X718956Y128002D01*
G01X738125Y119289D02*
X741979Y118610D01*
G01X737877Y118012D02*
X741979Y117289D01*
G01X722604Y122588D02*
X738125Y119289D01*
G01X722604Y121258D02*
X737877Y118012D01*
G01X718850Y121790D02*
X722604Y122588D01*
G01X718873Y120465D02*
X722604Y121258D01*
G01X705437Y124156D02*
X718850Y121790D01*
G01X705437Y122835D02*
X718873Y120465D01*
G01X714318Y110757D02*
X705695Y108924D01*
G01X718564Y108524D02*
X714318Y109427D01*
G01X718587Y109849D02*
X714318Y110757D01*
G01X731702Y110841D02*
X718564Y108524D01*
G01X731192Y112072D02*
X718587Y109849D01*
G01X733554Y112137D02*
X731702Y110841D01*
G01X733044Y113368D02*
X731192Y112072D01*
G01X758063Y116459D02*
X733554Y112137D01*
G01X758063Y117780D02*
X733044Y113368D01*
G01X722748Y124853D02*
X739696Y121250D01*
G01X722748Y126183D02*
X739696Y122580D01*
G01X719971Y124262D02*
X722748Y124853D01*
G01X719948Y125587D02*
X722748Y126183D01*
G01X706000Y126726D02*
X719971Y124262D01*
G01X706000Y128047D02*
X719948Y125587D01*
G01X721957Y128607D02*
X739409Y124898D01*
G01X721964Y129935D02*
X739409Y126228D01*
G01X718956Y128002D02*
X721957Y128607D01*
G01X718955Y129328D02*
X721964Y129935D01*
G01X705930Y130606D02*
X718956Y128002D01*
G01X705945Y131929D02*
X718955Y129328D01*
G01X737877Y118012D02*
X741979Y117289D01*
G01X738125Y119289D02*
X741979Y118610D01*
G01X722604Y121258D02*
X737877Y118012D01*
G01X722604Y122588D02*
X738125Y119289D01*
G01X718873Y120465D02*
X722604Y121258D01*
G01X718850Y121790D02*
X722604Y122588D01*
G01X705437Y122835D02*
X718873Y120465D01*
G01X705437Y124156D02*
X718850Y121790D01*
G01X737760Y129760D02*
X763142Y134234D01*
G01X737760Y131081D02*
X763142Y135555D01*
G01X721430Y132640D02*
X737760Y129760D01*
G01X729821Y132481D02*
X737760Y131081D01*
G01X721407Y133965D02*
X729821Y132481D01*
G01X718509Y132019D02*
X721430Y132640D01*
G01X718501Y133347D02*
X721407Y133965D01*
G01X705416Y134637D02*
X718509Y132019D01*
G01X705416Y135963D02*
X718501Y133347D01*
G01X737504Y139197D02*
X772250Y146134D01*
G01X737519Y137874D02*
X772265Y144811D01*
G01X721462Y142025D02*
X737504Y139197D01*
G01X721477Y140702D02*
X737519Y137874D01*
G01X717916Y141316D02*
X721462Y142025D01*
G01X717916Y139990D02*
X721477Y140702D01*
G01X705416Y143816D02*
X717916Y141316D01*
G01X705416Y142490D02*
X717916Y139990D01*
G01X737760Y131081D02*
X763142Y135555D01*
G01X737760Y129760D02*
X763142Y134234D01*
G01X729821Y132481D02*
X737760Y131081D01*
G01X721430Y132640D02*
X737760Y129760D01*
G01X721407Y133965D02*
X729821Y132481D01*
G01X721430Y132640D02*
X737760Y129760D01*
G01X718501Y133347D02*
X721407Y133965D01*
G01X718509Y132019D02*
X721430Y132640D01*
G01X705416Y135963D02*
X718501Y133347D01*
G01X705416Y134637D02*
X718509Y132019D01*
G01X737519Y137874D02*
X772265Y144811D01*
G01X737504Y139197D02*
X772250Y146134D01*
G01X721477Y140702D02*
X737519Y137874D01*
G01X721462Y142025D02*
X737504Y139197D01*
G01X717916Y139990D02*
X721477Y140702D01*
G01X717916Y141316D02*
X721462Y142025D01*
G01X705416Y142490D02*
X717916Y139990D01*
G01X705416Y143816D02*
X717916Y141316D01*
G01X738237Y133668D02*
X773187Y140657D01*
G01X738222Y134991D02*
X773172Y141980D01*
G01X721069Y136695D02*
X738237Y133668D01*
G01X721054Y138018D02*
X738222Y134991D01*
G01X717916Y136064D02*
X721069Y136695D01*
G01X717916Y137390D02*
X721054Y138018D01*
G01X705416Y138564D02*
X717916Y136064D01*
G01X705416Y139890D02*
X717916Y137390D01*
G01X738222Y134991D02*
X773172Y141980D01*
G01X738237Y133668D02*
X773187Y140657D01*
G01X721054Y138018D02*
X738222Y134991D01*
G01X721069Y136695D02*
X738237Y133668D01*
G01X717916Y137390D02*
X721054Y138018D01*
G01X717916Y136064D02*
X721069Y136695D01*
G01X705416Y139890D02*
X717916Y137390D01*
G01X705416Y138564D02*
X717916Y136064D01*
G01X735366Y143513D02*
X771502Y150741D01*
G01Y149415D02*
X735366Y142187D01*
G01X722314Y146123D02*
X735366Y143513D01*
G01Y142187D02*
X722314Y144797D01*
G01X717916Y145243D02*
X722314Y146123D01*
G01Y144797D02*
X717916Y143917D01*
G01X705506Y147725D02*
X717916Y145243D01*
G01Y143917D02*
X705506Y146399D01*
G01X717916Y143917D02*
X705506Y146399D01*
G01Y147725D02*
X717916Y145243D01*
G01X722314Y144797D02*
X717916Y143917D01*
G01Y145243D02*
X722314Y146123D01*
G01X735366Y142187D02*
X722314Y144797D01*
G01Y146123D02*
X735366Y143513D01*
G01X771502Y149415D02*
X735366Y142187D01*
G01Y143513D02*
X771502Y150741D01*
G01X724178Y149097D02*
X717922Y147846D01*
G01X724178Y150423D02*
X717929Y149174D01*
G01X736680Y146598D02*
X724178Y149097D01*
G01X736680Y147924D02*
X724178Y150423D01*
G01X771943Y153649D02*
X736680Y146598D01*
G01X771943Y154975D02*
X736680Y147924D01*
G01X724116Y158263D02*
X717916Y157023D01*
G01X724116Y156937D02*
X717916Y155697D01*
G01X736616Y155763D02*
X724116Y158263D01*
G01X736616Y154437D02*
X724116Y156937D01*
G01X776572Y163754D02*
X736616Y155763D01*
G01X776564Y162426D02*
X736616Y154437D01*
G01X724178Y150423D02*
X717929Y149174D01*
G01X724178Y149097D02*
X717922Y147846D01*
G01X736680Y147924D02*
X724178Y150423D01*
G01X736680Y146598D02*
X724178Y149097D01*
G01X771943Y154975D02*
X736680Y147924D01*
G01X771943Y153649D02*
X736680Y146598D01*
G01X724116Y156937D02*
X717916Y155697D01*
G01X724116Y158263D02*
X717916Y157023D01*
G01X736616Y154437D02*
X724116Y156937D01*
G01X736616Y155763D02*
X724116Y158263D01*
G01X776564Y162426D02*
X736616Y154437D01*
G01X776572Y163754D02*
X736616Y155763D01*
G01X717917Y160950D02*
X717916D01*
G01X723447Y160730D02*
X717916Y159624D01*
G01X723447Y162056D02*
X717917Y160950D01*
G01X723447Y160730D02*
X717916Y159624D01*
G01X729695Y160808D02*
X723447Y162056D01*
G01X735955Y158229D02*
X723447Y160730D01*
G01X735947Y159557D02*
X729695Y160807D01*
G01X735955Y158229D02*
X723447Y160730D01*
G01X775363Y167935D02*
X735947Y159557D01*
G01X775363Y166605D02*
X735955Y158229D01*
G01X736832Y150553D02*
X776413Y158468D01*
G01X736832Y151879D02*
X776421Y159796D01*
G01X724332Y153053D02*
X736832Y150553D01*
G01X724332Y154379D02*
X736832Y151879D01*
G01X717916Y151770D02*
X724332Y153053D01*
G01X717916Y153096D02*
X724332Y154379D01*
G01X717917Y160950D02*
X717916D01*
G01X723447Y160730D02*
X717916Y159624D01*
G01X717917Y160950D02*
X717916D01*
G01X723447Y162056D02*
X717917Y160950D01*
G01X735955Y158229D02*
X723447Y160730D01*
G01X729695Y160808D02*
X723447Y162056D01*
G01X735947Y159557D02*
X729695Y160807D01*
G01X775363Y166605D02*
X735955Y158229D01*
G01X775363Y167935D02*
X735947Y159557D01*
G01X736832Y151879D02*
X776421Y159796D01*
G01X736832Y150553D02*
X776413Y158468D01*
G01X724332Y154379D02*
X736832Y151879D01*
G01X724332Y153053D02*
X736832Y150553D01*
G01X717916Y153096D02*
X724332Y154379D01*
G01X717916Y151770D02*
X724332Y153053D01*
G01X770170Y174477D02*
X717891Y163647D01*
G01X770170Y174477D02*
X717891Y163647D01*
G01X770170Y174477D02*
X717891Y163647D01*
G01X770170Y174477D02*
X717891Y163647D01*
G01X717894Y164976D02*
X751765Y171992D01*
G01X770170Y174477D02*
X717891Y163647D01*
G01X770170Y174477D02*
X717891Y163647D01*
G01X717894Y164976D02*
X751765Y171992D01*
G01X763867Y181040D02*
X714508Y170546D01*
G01Y171876D02*
X734917Y176215D01*
G01X763867Y181040D02*
X714508Y170546D01*
G01X763867Y181040D02*
X714508Y170546D01*
G01X763867Y181040D02*
X714508Y170546D01*
G01X763867Y181040D02*
X714508Y170546D01*
G01Y171876D02*
X734917Y176215D01*
G01X763867Y181040D02*
X714508Y170546D01*
G01X737900Y176849D02*
X739514Y177192D01*
G01X737900Y176849D02*
X739514Y177192D01*
G01X712754Y349889D02*
X749673Y297164D01*
G01X748442Y296654D02*
X711820Y348955D01*
G01X748442Y296654D02*
X711820Y348955D01*
G01X712754Y349889D02*
X749673Y297164D01*
G01X712566Y350021D02*
X712754Y349889D01*
G01X712566Y350021D02*
X712754Y349889D01*
G01X735754Y707018D02*
X723769Y774990D01*
G01X736985Y707528D02*
X725000Y775500D01*
G01X922070Y440931D02*
X735754Y707018D01*
G01X923301Y441441D02*
X736985Y707528D01*
G01D02*
X725000Y775500D01*
G01X735754Y707018D02*
X723769Y774990D01*
G01X923301Y441441D02*
X736985Y707528D01*
G01X922070Y440931D02*
X735754Y707018D01*
G01X722400Y816200D02*
X706049Y831184D01*
G01X737185Y807112D02*
X722400Y816200D01*
G01X736553Y809028D02*
X723187Y817243D01*
G01X738096Y808079D02*
X736554Y809027D01*
G01X752221Y785638D02*
X737185Y807112D01*
G01X739614Y805912D02*
X738096Y808079D01*
G01X737652Y814078D02*
X723400Y820200D01*
G01X738506Y815126D02*
X724146Y821296D01*
G01X756269Y787490D02*
X737652Y814078D01*
G01X757500Y788000D02*
X738586Y815012D01*
G01X722400Y816200D02*
X706049Y831184D01*
G01X736553Y809028D02*
X723187Y817243D01*
G01X737185Y807112D02*
X722400Y816200D01*
G01X738096Y808079D02*
X736554Y809027D01*
G01X737185Y807112D02*
X722400Y816200D01*
G01X739614Y805912D02*
X738096Y808079D01*
G01X752221Y785638D02*
X737185Y807112D01*
G01X752221Y785638D02*
X737185Y807112D01*
G01X752221Y785638D02*
X737185Y807112D01*
G01X738506Y815126D02*
X724146Y821296D01*
G01X737652Y814078D02*
X723400Y820200D01*
G01X757500Y788000D02*
X738586Y815012D01*
G01X756269Y787490D02*
X737652Y814078D01*
G01X740922Y847236D02*
X736226Y850525D01*
G01X740922Y847236D02*
X736226Y850525D01*
G01X707033Y832047D02*
X706983Y832118D01*
G01X723187Y817243D02*
X707033Y832047D01*
G01X711928Y833629D02*
X711860Y833726D01*
G01X723400Y820200D02*
X710926Y832792D01*
G01X724146Y821296D02*
X711928Y833629D01*
G01X707033Y832047D02*
X706983Y832118D01*
G01X723187Y817243D02*
X707033Y832047D01*
G01X711928Y833629D02*
X711860Y833726D01*
G01X724146Y821296D02*
X711928Y833629D01*
G01X723400Y820200D02*
X710926Y832792D01*
G01X736108Y863706D02*
X749063Y854635D01*
G01X737042Y864640D02*
X749997Y855569D01*
G01X732027Y869535D02*
X736108Y863706D01*
G01X733327Y869946D02*
X737042Y864640D01*
G01X732027Y872882D02*
Y869535D01*
G01X733327Y872882D02*
Y869946D01*
G01X737042Y864640D02*
X749997Y855569D01*
G01X736108Y863706D02*
X749063Y854635D01*
G01X733327Y869946D02*
X737042Y864640D01*
G01X732027Y869535D02*
X736108Y863706D01*
G01X733327Y872882D02*
Y869946D01*
G01X732027Y872882D02*
Y869535D01*
G01X714100Y853279D02*
X705672Y854765D01*
G01X714100Y854600D02*
X706182Y855996D01*
G01X721969Y854667D02*
X714100Y853279D01*
G01X721969Y855988D02*
X714100Y854600D01*
G01X729366Y853362D02*
X721969Y854667D01*
G01X729732Y854618D02*
X721969Y855988D01*
G01X736222Y850527D02*
X729366Y853362D01*
G01X736762Y851711D02*
X729732Y854618D01*
G01X736770Y851707D02*
X736762Y851711D01*
G01X741856Y848170D02*
X736792Y851716D01*
G01X714100Y854600D02*
X706182Y855996D01*
G01X714100Y853279D02*
X705672Y854765D01*
G01X721969Y855988D02*
X714100Y854600D01*
G01X721969Y854667D02*
X714100Y853279D01*
G01X729732Y854618D02*
X721969Y855988D01*
G01X729366Y853362D02*
X721969Y854667D01*
G01X736762Y851711D02*
X729732Y854618D01*
G01X736222Y850527D02*
X729366Y853362D01*
G01X736770Y851707D02*
X736762Y851711D01*
G01X736222Y850527D02*
X729366Y853362D01*
G01X741856Y848170D02*
X736792Y851716D01*
G01X746721Y38420D02*
X760710Y52409D01*
G01X745801Y39340D02*
X759790Y53329D01*
G01X744014Y37300D02*
G03X746721Y38420I1J3828D01*
G01X744015Y38600D02*
G03X745801Y39340I-1J2528D01*
G01X740292Y38600D02*
X744015D01*
G01X745801Y39340D02*
X759790Y53329D01*
G01X746721Y38420D02*
X760710Y52409D01*
G01X744015Y38600D02*
G03X745801Y39340I-1J2528D01*
G01X744014Y37300D02*
G03X746721Y38420I1J3828D01*
G01X740292Y38600D02*
X744015D01*
G01X772150Y58600D02*
G03X775650Y60049I1J4948D01*
G01X772151Y59900D02*
G03X774730Y60969I-1J3648D01*
G01X760912Y58600D02*
X772150D01*
G01X760912Y59900D02*
X772151D01*
G01X759594Y58054D02*
G02X760912Y58600I1318J-1318D01*
G01X758674Y58974D02*
G02X760912Y59900I2237J-2238D01*
G01X749712Y48172D02*
X759594Y58054D01*
G01X748792Y49092D02*
X758674Y58974D01*
G01X746882Y47001D02*
G03X749712Y48172I1J4002D01*
G01X746883Y48301D02*
G03X748792Y49092I-1J2702D01*
G01X741659Y48301D02*
X746883D01*
G01X772151Y59900D02*
G03X774730Y60969I-1J3648D01*
G01X772150Y58600D02*
G03X775650Y60049I1J4948D01*
G01X760912Y59900D02*
X772151D01*
G01X760912Y58600D02*
X772150D01*
G01X758674Y58974D02*
G02X760912Y59900I2237J-2238D01*
G01X759594Y58054D02*
G02X760912Y58600I1318J-1318D01*
G01X748792Y49092D02*
X758674Y58974D01*
G01X749712Y48172D02*
X759594Y58054D01*
G01X746883Y48301D02*
G03X748792Y49092I-1J2702D01*
G01X746882Y47001D02*
G03X749712Y48172I1J4002D01*
G01X741659Y48301D02*
X746883D01*
G01X762620Y53200D02*
X773260D01*
G01X762620Y54500D02*
X773261D01*
G01X760710Y52409D02*
G02X762620Y53200I1910J-1911D01*
G01X759790Y53329D02*
G02X762620Y54500I2829J-2831D01*
G01D02*
X773261D01*
G01X762620Y53200D02*
X773260D01*
G01X759790Y53329D02*
G02X762620Y54500I2829J-2831D01*
G01X760710Y52409D02*
G02X762620Y53200I1910J-1911D01*
G01X739753Y62572D02*
X780334Y90990D01*
G01X740263Y61341D02*
X780863Y89773D01*
G01X740263Y61341D02*
X780863Y89773D01*
G01X739753Y62572D02*
X780334Y90990D01*
G01X753045Y106702D02*
X775817Y110718D01*
G01X753555Y105471D02*
X775817Y109397D01*
G01X742305Y99180D02*
X753045Y106702D01*
G01X743258Y98260D02*
X753555Y105471D01*
G01X769506Y94734D02*
X784649Y97950D01*
G01X769775Y93461D02*
X784649Y96620D01*
G01X769505Y94733D02*
X769506D01*
G01X769775Y93461D02*
X784649Y96620D01*
G01X769246Y94678D02*
X769505Y94733D01*
G01X769775Y93461D02*
X784649Y96620D01*
G01X753555Y105471D02*
X775817Y109397D01*
G01X753045Y106702D02*
X775817Y110718D01*
G01X743258Y98260D02*
X753555Y105471D01*
G01X742305Y99180D02*
X753045Y106702D01*
G01X769775Y93461D02*
X784649Y96620D01*
G01X769506Y94734D02*
X784649Y97950D01*
G01X769505Y94733D02*
X769506D01*
G01X769246Y94678D02*
X769505Y94733D01*
G01X779506Y113999D02*
X758063Y117780D01*
G01X779506Y112678D02*
X758063Y116459D01*
G01X757103Y126280D02*
X782995Y121669D01*
G01X757125Y124955D02*
X782994Y120348D01*
G01X739696Y122580D02*
X757103Y126280D01*
G01X739696Y121250D02*
X757125Y124955D01*
G01X762435Y131124D02*
X780442Y127295D01*
G01X762435Y129794D02*
X780442Y125965D01*
G01X739409Y126228D02*
X762435Y131124D01*
G01X739409Y124898D02*
X762435Y129794D01*
G01X758390Y121504D02*
X781135Y117493D01*
G01X758390Y120183D02*
X781135Y116172D01*
G01X741979Y118610D02*
X758390Y121504D01*
G01X741979Y117289D02*
X758390Y120183D01*
G01X779506Y112678D02*
X758063Y116459D01*
G01X779506Y113999D02*
X758063Y117780D01*
G01X757125Y124955D02*
X782994Y120348D01*
G01X757103Y126280D02*
X782995Y121669D01*
G01X739696Y121250D02*
X757125Y124955D01*
G01X739696Y122580D02*
X757103Y126280D01*
G01X762435Y129794D02*
X780442Y125965D01*
G01X762435Y131124D02*
X780442Y127295D01*
G01X739409Y124898D02*
X762435Y129794D01*
G01X739409Y126228D02*
X762435Y131124D01*
G01X758390Y120183D02*
X781135Y116172D01*
G01X758390Y121504D02*
X781135Y117493D01*
G01X741979Y117289D02*
X758390Y120183D01*
G01X741979Y118610D02*
X758390Y121504D01*
G01X763142Y134234D02*
X781866Y130935D01*
G01X763142Y135555D02*
X781848Y132259D01*
G01X763142Y135555D02*
X781848Y132259D01*
G01X763142Y134234D02*
X781866Y130935D01*
G01X772250Y146134D02*
X838494Y134451D01*
G01X772265Y144811D02*
X838494Y133130D01*
G01X771502Y150741D02*
X804575Y144126D01*
G01X804335Y142848D02*
X771502Y149415D01*
G01X772265Y144811D02*
X838494Y133130D01*
G01X772250Y146134D02*
X838494Y134451D01*
G01X804335Y142848D02*
X771502Y149415D01*
G01Y150741D02*
X804575Y144126D01*
G01X805450Y146948D02*
X771943Y153649D01*
G01X805690Y148226D02*
X771943Y154975D01*
G01X805690Y148226D02*
X771943Y154975D01*
G01X805450Y146948D02*
X771943Y153649D01*
G01X770174Y175806D02*
X777566Y174234D01*
G01Y172904D02*
X770170Y174477D01*
G01X763956Y174518D02*
X765572Y174853D01*
G01X759354Y173564D02*
X760969Y173899D01*
G01X754751Y172611D02*
X756367Y172946D01*
G01X763956Y174518D02*
X765572Y174853D01*
G01X759354Y173564D02*
X760969Y173899D01*
G01X754751Y172611D02*
X756367Y172946D01*
G01X777566Y172904D02*
X770170Y174477D01*
G01X770174Y175806D02*
X777566Y174234D01*
G01X771405Y197594D02*
X785017Y188064D01*
G01X784488Y186847D02*
X770471Y196660D01*
G01X756038Y219544D02*
X771405Y197594D01*
G01X770471Y196660D02*
X754807Y219034D01*
G01X770471Y196660D02*
X754807Y219034D01*
G01X756038Y219544D02*
X771405Y197594D01*
G01X784488Y186847D02*
X770471Y196660D01*
G01X771405Y197594D02*
X785017Y188064D01*
G01X768558Y175471D02*
X770174Y175806D01*
G01X768558Y175471D02*
X770174Y175806D01*
G01X751692Y179781D02*
X763730Y182340D01*
G01X747095Y178804D02*
X748709Y179147D01*
G01X742497Y177826D02*
X744111Y178169D01*
G01X777257Y181040D02*
X763867D01*
G01X763730Y182340D02*
X777257D01*
G01X763730D02*
X777257D01*
G01Y181040D02*
X763867D01*
G01X751692Y179781D02*
X763730Y182340D01*
G01X747095Y178804D02*
X748709Y179147D01*
G01X742497Y177826D02*
X744111Y178169D01*
G01X759785Y221435D02*
X773951Y201200D01*
G01X758554Y220925D02*
X773017Y200266D01*
G01X758554Y220925D02*
X773017Y200266D01*
G01X759785Y221435D02*
X773951Y201200D01*
G01X752499Y239619D02*
X756038Y219544D01*
G01X754807Y219034D02*
X751199Y239505D01*
G01X752499Y240187D02*
Y239619D01*
G01X751199Y239505D02*
Y240301D01*
G01X756109Y260659D02*
X752499Y240187D01*
G01X751199Y240301D02*
X754788Y260659D01*
G01X751199Y240301D02*
X754788Y260659D01*
G01X756109D02*
X752499Y240187D01*
G01X751199Y239505D02*
Y240301D01*
G01X752499Y240187D02*
Y239619D01*
G01X754807Y219034D02*
X751199Y239505D01*
G01X752499Y239619D02*
X756038Y219544D01*
G01X772023Y225667D02*
X774655Y221912D01*
G01X773722Y220978D02*
X770949Y224933D01*
G01X771046Y227133D02*
X772023Y225667D01*
G01X770949Y224933D02*
X769812Y226639D01*
G01X768973Y238908D02*
X771046Y227133D01*
G01X769812Y226639D02*
X767652Y238908D01*
G01X772906Y261212D02*
X768973Y238908D01*
G01X767652D02*
X771585Y261212D01*
G01X767652Y238908D02*
X771585Y261212D01*
G01X772906D02*
X768973Y238908D01*
G01X769812Y226639D02*
X767652Y238908D01*
G01X768973D02*
X771046Y227133D01*
G01X770949Y224933D02*
X769812Y226639D01*
G01X771046Y227133D02*
X772023Y225667D01*
G01X773722Y220978D02*
X770949Y224933D01*
G01X772023Y225667D02*
X774655Y221912D01*
G01X771703Y238937D02*
X773442Y228882D01*
G01X775688Y261551D02*
X771703Y238941D01*
G01Y238937D02*
X773442Y228882D01*
G01X775688Y261551D02*
X771703Y238941D01*
G01X756700Y238959D02*
X759785Y221435D01*
G01X755380Y238957D02*
X758554Y220925D01*
G01X760471Y260800D02*
X756700Y238959D01*
G01X759151Y260798D02*
X755380Y238957D01*
G01D02*
X758554Y220925D01*
G01X756700Y238959D02*
X759785Y221435D01*
G01X759151Y260798D02*
X755380Y238957D01*
G01X760471Y260800D02*
X756700Y238959D01*
G01X772006Y218837D02*
X792401Y204556D01*
G01X791991Y203256D02*
X771073Y217903D01*
G01X767220Y225668D02*
X772006Y218837D01*
G01X771073Y217903D02*
X765989Y225158D01*
G01X764866Y239036D02*
X767220Y225668D01*
G01X765989Y225158D02*
X763545Y239036D01*
G01X768776Y261217D02*
X764866Y239036D01*
G01X763545D02*
X767455Y261217D01*
G01X763545Y239036D02*
X767455Y261217D01*
G01X768776D02*
X764866Y239036D01*
G01X765989Y225158D02*
X763545Y239036D01*
G01X764866D02*
X767220Y225668D01*
G01X771073Y217903D02*
X765989Y225158D01*
G01X767220Y225668D02*
X772006Y218837D01*
G01X791991Y203256D02*
X771073Y217903D01*
G01X772006Y218837D02*
X792401Y204556D01*
G01X770315Y211776D02*
X788949Y199675D01*
G01X789658Y200765D02*
X771024Y212867D01*
G01X769807Y212267D02*
G03X770315Y211776I1517J1061D01*
G01X771024Y212867D02*
G02X770873Y213013I300J461D01*
G01X766087Y217579D02*
X769807Y212267D01*
G01X770873Y213013D02*
X763431Y223639D01*
G01X762200Y223129D02*
X766087Y217579D01*
G01X770873Y213013D02*
X763431Y223639D01*
G01X759449Y238752D02*
X762200Y223129D01*
G01X763431Y223639D02*
X760770Y238752D01*
G01X763326Y260762D02*
X759449Y238752D01*
G01X760770D02*
X764647Y260762D01*
G01X760770Y238752D02*
X764647Y260762D01*
G01X763326D02*
X759449Y238752D01*
G01X763431Y223639D02*
X760770Y238752D01*
G01X759449D02*
X762200Y223129D01*
G01X770873Y213013D02*
X763431Y223639D01*
G01X766087Y217579D02*
X769807Y212267D01*
G01X762200Y223129D02*
X766087Y217579D01*
G01X771024Y212867D02*
G02X770873Y213013I300J461D01*
G01X769807Y212267D02*
G03X770315Y211776I1517J1061D01*
G01X789658Y200765D02*
X771024Y212867D01*
G01X770315Y211776D02*
X788949Y199675D01*
G01X749673Y297164D02*
X756109Y260659D01*
G01X754788D02*
X748442Y296654D01*
G01X754788Y260659D02*
X748442Y296654D01*
G01X749673Y297164D02*
X756109Y260659D01*
G01X765550Y302938D02*
X772906Y261212D01*
G01X771585D02*
X764319Y302428D01*
G01X771585Y261212D02*
X764319Y302428D01*
G01X765550Y302938D02*
X772906Y261212D01*
G01X753953Y297771D02*
X760471Y260800D01*
G01X752722Y297261D02*
X759151Y260798D01*
G01X752722Y297261D02*
X759151Y260798D01*
G01X753953Y297771D02*
X760471Y260800D01*
G01X761694Y301396D02*
X768776Y261217D01*
G01X767455D02*
X760463Y300886D01*
G01X767455Y261217D02*
X760463Y300886D01*
G01X761694Y301396D02*
X768776Y261217D01*
G01X756587Y298990D02*
X763326Y260762D01*
G01X764647D02*
X757818Y299500D01*
G01X764647Y260762D02*
X757818Y299500D01*
G01X756587Y298990D02*
X763326Y260762D01*
G01X769487Y304186D02*
X777009Y261551D01*
G01X768256Y303676D02*
X775688Y261551D01*
G01X768256Y303676D02*
X775688Y261551D01*
G01X769487Y304186D02*
X777009Y261551D01*
G01X773915Y662604D02*
X752221Y785638D01*
G01X775146Y663114D02*
X753452Y786148D01*
G01X775146Y663114D02*
X753452Y786148D01*
G01X773915Y662604D02*
X752221Y785638D01*
G01X777463Y667290D02*
X756269Y787490D01*
G01X778694Y667800D02*
X757500Y788000D01*
G01X778694Y667800D02*
X757500Y788000D01*
G01X777463Y667290D02*
X756269Y787490D01*
G01X787795Y660476D02*
X761938Y807122D01*
G01X787795Y660476D02*
X761938Y807122D01*
G01X765875Y813341D02*
X792791Y660679D01*
G01X765875Y813341D02*
X792791Y660679D01*
G01X789026Y660986D02*
X763148Y807752D01*
G01X789026Y660986D02*
X763148Y807752D01*
G01X796982Y663765D02*
X769357Y820438D01*
G01X798213Y664275D02*
X770678Y820438D01*
G01X798213Y664275D02*
X770678Y820438D01*
G01X796982Y663765D02*
X769357Y820438D01*
G01X767106Y813851D02*
X794022Y661189D01*
G01X757480Y825333D02*
X765875Y813341D01*
G01X758780Y825743D02*
X767106Y813851D01*
G01D02*
X794022Y661189D01*
G01X758780Y825743D02*
X767106Y813851D01*
G01X757480Y825333D02*
X765875Y813341D01*
G01X761938Y807122D02*
X744400Y824661D01*
G01X763148Y807752D02*
X745700Y825200D01*
G01X763148Y807752D02*
X745700Y825200D01*
G01X761938Y807122D02*
X744400Y824661D01*
G01X740251Y805000D02*
X739614Y805912D01*
G01X753452Y786148D02*
X740251Y805000D01*
G01D02*
X739614Y805912D01*
G01X753452Y786148D02*
X740251Y805000D01*
G01X768854Y846910D02*
X765598Y851559D01*
G01X770085Y847420D02*
X766532Y852493D01*
G01X769900Y840986D02*
X768854Y846910D01*
G01X771200Y841100D02*
X770085Y847420D01*
G01X769900Y823514D02*
Y840986D01*
G01X771200Y823400D02*
Y841100D01*
G01X769357Y820438D02*
X769900Y823514D01*
G01X770678Y820438D02*
X771200Y823400D01*
G01X770085Y847420D02*
X766532Y852493D01*
G01X768854Y846910D02*
X765598Y851559D01*
G01X771200Y841100D02*
X770085Y847420D01*
G01X769900Y840986D02*
X768854Y846910D01*
G01X771200Y823400D02*
Y841100D01*
G01X769900Y823514D02*
Y840986D01*
G01X770678Y820438D02*
X771200Y823400D01*
G01X769357Y820438D02*
X769900Y823514D01*
G01X757480Y840886D02*
Y825333D01*
G01X758780Y841000D02*
Y825743D01*
G01X757072Y843196D02*
X757480Y840886D01*
G01X758303Y843706D02*
X758780Y841000D01*
G01X749063Y854635D02*
X757072Y843196D01*
G01X749997Y855569D02*
X758303Y843706D01*
G01X758780Y841000D02*
Y825743D01*
G01X757480Y840886D02*
Y825333D01*
G01X758303Y843706D02*
X758780Y841000D01*
G01X757072Y843196D02*
X757480Y840886D01*
G01X749997Y855569D02*
X758303Y843706D01*
G01X749063Y854635D02*
X757072Y843196D01*
G01X743837Y843072D02*
X740922Y847236D01*
G01X745068Y843582D02*
X741856Y848170D01*
G01X744400Y839886D02*
X743837Y843072D01*
G01X745700Y840000D02*
X745068Y843582D01*
G01X744400Y824661D02*
Y839886D01*
G01X745700Y825200D02*
Y840000D01*
G01X745068Y843582D02*
X741856Y848170D01*
G01X743837Y843072D02*
X740922Y847236D01*
G01X745700Y840000D02*
X745068Y843582D01*
G01X744400Y839886D02*
X743837Y843072D01*
G01X745700Y825200D02*
Y840000D01*
G01X744400Y824661D02*
Y839886D01*
G01X761561Y865803D02*
X774330Y856862D01*
G01X762495Y866737D02*
X775264Y857796D01*
G01X757224Y871998D02*
X761561Y865803D01*
G01X758524Y872409D02*
X762495Y866737D01*
G01X757224Y872882D02*
Y871998D01*
G01X758524Y872882D02*
Y872409D01*
G01X769823Y871043D02*
X772835Y866739D01*
G01X771123Y871453D02*
X773769Y867673D01*
G01X769823Y872882D02*
Y871043D01*
G01X771123Y872882D02*
Y871453D01*
G01X762495Y866737D02*
X775264Y857796D01*
G01X761561Y865803D02*
X774330Y856862D01*
G01X758524Y872409D02*
X762495Y866737D01*
G01X757224Y871998D02*
X761561Y865803D01*
G01X758524Y872882D02*
Y872409D01*
G01X757224Y872882D02*
Y871998D01*
G01X771123Y871453D02*
X773769Y867673D01*
G01X769823Y871043D02*
X772835Y866739D01*
G01X771123Y872882D02*
Y871453D01*
G01X769823Y872882D02*
Y871043D01*
G01X744626Y868567D02*
Y872882D01*
G01X745926Y868977D02*
Y872882D01*
G01X747817Y864009D02*
X744626Y868567D01*
G01X748751Y864943D02*
X745926Y868977D01*
G01X765598Y851559D02*
X747817Y864009D01*
G01X766532Y852493D02*
X748751Y864943D01*
G01X745926Y868977D02*
Y872882D01*
G01X744626Y868567D02*
Y872882D01*
G01X748751Y864943D02*
X745926Y868977D01*
G01X747817Y864009D02*
X744626Y868567D01*
G01X766532Y852493D02*
X748751Y864943D01*
G01X765598Y851559D02*
X747817Y864009D01*
G01X781462Y63600D02*
X914464D01*
G01X781461Y64900D02*
X895663D01*
G01X777602Y62001D02*
G02X781462Y63600I3861J-3861D01*
G01X776682Y62921D02*
G02X781461Y64900I4779J-4781D01*
G01X775650Y60049D02*
X777602Y62001D01*
G01X774730Y60969D02*
X776682Y62921D01*
G01X781462Y63600D02*
X914464D01*
G01X781462D02*
X914464D01*
G01X781462D02*
X914464D01*
G01X781462D02*
X914464D01*
G01X781461Y64900D02*
X895663D01*
G01X781462Y63600D02*
X914464D01*
G01X776682Y62921D02*
G02X781461Y64900I4779J-4781D01*
G01X777602Y62001D02*
G02X781462Y63600I3861J-3861D01*
G01X774730Y60969D02*
X776682Y62921D01*
G01X775650Y60049D02*
X777602Y62001D01*
G01X781547Y58400D02*
X913392D01*
G01X781546Y59700D02*
X894593D01*
G01X780102Y57801D02*
G02X781547Y58400I1446J-1445D01*
G01X779182Y58721D02*
G02X781546Y59700I2364J-2365D01*
G01X777084Y54783D02*
X780102Y57801D01*
G01X776164Y55703D02*
X779182Y58721D01*
G01X773260Y53200D02*
G03X777084Y54783I1J5407D01*
G01X773261Y54500D02*
G03X776164Y55703I-1J4107D01*
G01X781547Y58400D02*
X913392D01*
G01X781547D02*
X913392D01*
G01X781547D02*
X913392D01*
G01X781547D02*
X913392D01*
G01X781546Y59700D02*
X894593D01*
G01X781547Y58400D02*
X913392D01*
G01X779182Y58721D02*
G02X781546Y59700I2364J-2365D01*
G01X780102Y57801D02*
G02X781547Y58400I1446J-1445D01*
G01X776164Y55703D02*
X779182Y58721D01*
G01X777084Y54783D02*
X780102Y57801D01*
G01X773261Y54500D02*
G03X776164Y55703I-1J4107D01*
G01X773260Y53200D02*
G03X777084Y54783I1J5407D01*
G01X795177Y89308D02*
X813612Y93227D01*
G01X795177Y87978D02*
X813612Y91897D01*
G01X783799Y91726D02*
X795177Y89308D01*
G01X783799Y90396D02*
X795177Y87978D01*
G01X780334Y90990D02*
X783799Y91726D01*
G01X780863Y89773D02*
X783799Y90396D01*
G01X800110Y108863D02*
X809764Y106811D01*
G01X804927Y106509D02*
X809741Y105486D01*
G01X800110Y107533D02*
X804927Y106509D01*
G01X772932Y103084D02*
X800110Y108863D01*
G01X773461Y101867D02*
X800110Y107533D01*
G01X795177Y87978D02*
X813612Y91897D01*
G01X795177Y89308D02*
X813612Y93227D01*
G01X783799Y90396D02*
X795177Y87978D01*
G01X783799Y91726D02*
X795177Y89308D01*
G01X780863Y89773D02*
X783799Y90396D01*
G01X780334Y90990D02*
X783799Y91726D01*
G01X804927Y106509D02*
X809741Y105486D01*
G01X800110Y108863D02*
X809764Y106811D01*
G01X800110Y107533D02*
X804927Y106509D01*
G01X800110Y108863D02*
X809764Y106811D01*
G01X773461Y101867D02*
X800110Y107533D01*
G01X772932Y103084D02*
X800110Y108863D01*
G01X794309Y95897D02*
X809806Y99191D01*
G01X794309Y94567D02*
X810603Y98031D01*
G01X784649Y97950D02*
X794309Y95897D01*
G01X784649Y96620D02*
X794309Y94567D01*
G01D02*
X810603Y98031D01*
G01X794309Y95897D02*
X809806Y99191D01*
G01X784649Y96620D02*
X794309Y94567D01*
G01X784649Y97950D02*
X794309Y95897D01*
G01X782647Y109513D02*
X806235Y114527D01*
G01X782670Y108188D02*
X806258Y113202D01*
G01X775817Y110718D02*
X782647Y109513D01*
G01X775817Y109397D02*
X782670Y108188D01*
G01D02*
X806258Y113202D01*
G01X782647Y109513D02*
X806235Y114527D01*
G01X775817Y109397D02*
X782670Y108188D01*
G01X775817Y110718D02*
X782647Y109513D01*
G01X805463Y118575D02*
X779506Y113999D01*
G01X805463Y117254D02*
X779506Y112678D01*
G01X826404Y114884D02*
X805463Y118575D01*
G01X825894Y113653D02*
X805463Y117254D01*
G01X803251Y125242D02*
X831616Y120240D01*
G01X803251Y123921D02*
X831106Y119009D01*
G01X782995Y121669D02*
X803251Y125242D01*
G01X782994Y120348D02*
X803251Y123921D01*
G01X794533Y130290D02*
X832468Y123601D01*
G01X794556Y128965D02*
X831958Y122370D01*
G01X780442Y127295D02*
X794533Y130290D01*
G01X780442Y125965D02*
X794556Y128965D01*
G01X805148Y121730D02*
X828961Y117532D01*
G01X805148Y120409D02*
X828451Y116301D01*
G01X781135Y117493D02*
X805148Y121730D01*
G01X781135Y116172D02*
X805148Y120409D01*
G01X805463Y117254D02*
X779506Y112678D01*
G01X805463Y118575D02*
X779506Y113999D01*
G01X825894Y113653D02*
X805463Y117254D01*
G01X826404Y114884D02*
X805463Y118575D01*
G01X803251Y123921D02*
X831106Y119009D01*
G01X803251Y125242D02*
X831616Y120240D01*
G01X782994Y120348D02*
X803251Y123921D01*
G01X782995Y121669D02*
X803251Y125242D01*
G01X794556Y128965D02*
X831958Y122370D01*
G01X794533Y130290D02*
X832468Y123601D01*
G01X780442Y125965D02*
X794556Y128965D01*
G01X780442Y127295D02*
X794533Y130290D01*
G01X805148Y120409D02*
X828451Y116301D01*
G01X805148Y121730D02*
X828961Y117532D01*
G01X781135Y116172D02*
X805148Y120409D01*
G01X781135Y117493D02*
X805148Y121730D01*
G01X793239Y133251D02*
X839474Y125097D01*
G01X793222Y134575D02*
X839474Y126418D01*
G01X781866Y130935D02*
X793239Y133251D01*
G01X781848Y132259D02*
X793222Y134575D01*
G01D02*
X839474Y126418D01*
G01X793239Y133251D02*
X839474Y125097D01*
G01X781848Y132259D02*
X793222Y134575D01*
G01X781866Y130935D02*
X793239Y133251D01*
G01X806001Y134869D02*
X838813Y129084D01*
G01X773172Y141980D02*
X838813Y130405D01*
G01X773187Y140657D02*
X806001Y134870D01*
G01X773172Y141980D02*
X838813Y130405D01*
G01X773172Y141980D02*
X838813Y130405D01*
G01X806001Y134869D02*
X838813Y129084D01*
G01X773187Y140657D02*
X806001Y134870D01*
G01X804575Y144126D02*
X837335Y138349D01*
G01Y137028D02*
X804335Y142848D01*
G01X837335Y137028D02*
X804335Y142848D01*
G01X804575Y144126D02*
X837335Y138349D01*
G01X837888Y141227D02*
X805450Y146948D01*
G01X837888Y142548D02*
X805690Y148226D01*
G01X837801Y150738D02*
X776572Y163754D01*
G01X837779Y149413D02*
X776564Y162426D01*
G01X837888Y142548D02*
X805690Y148226D01*
G01X837888Y141227D02*
X805450Y146948D01*
G01X837779Y149413D02*
X776564Y162426D01*
G01X837801Y150738D02*
X776572Y163754D01*
G01X837276Y154776D02*
X775363Y167935D01*
G01X837254Y153451D02*
X775363Y166605D01*
G01X776413Y158468D02*
X829968Y147086D01*
G01X776421Y159796D02*
X830238Y148358D01*
G01X837254Y153451D02*
X775363Y166605D01*
G01X837276Y154776D02*
X775363Y167935D01*
G01X776421Y159796D02*
X830238Y148358D01*
G01X776413Y158468D02*
X829968Y147086D01*
G01X782739Y175333D02*
X788224Y178893D01*
G01X788609Y177593D02*
X783245Y174111D01*
G01X777566Y174234D02*
X782739Y175333D01*
G01X783245Y174111D02*
X777566Y172904D01*
G01X783245Y174111D02*
X777566Y172904D01*
G01Y174234D02*
X782739Y175333D01*
G01X788609Y177593D02*
X783245Y174111D01*
G01X782739Y175333D02*
X788224Y178893D01*
G01X799215Y185046D02*
X821579Y170522D01*
G01X821073Y169300D02*
X798709Y183824D01*
G01X785017Y188064D02*
X799215Y185046D01*
G01X798709Y183824D02*
X784488Y186847D01*
G01X798709Y183824D02*
X784488Y186847D01*
G01X785017Y188064D02*
X799215Y185046D01*
G01X821073Y169300D02*
X798709Y183824D01*
G01X799215Y185046D02*
X821579Y170522D01*
G01X788224Y178893D02*
X791210D01*
G01Y177593D02*
X788609D01*
G01X791210D02*
X788609D01*
G01X788224Y178893D02*
X791210D01*
G01X801713Y208712D02*
X807300Y204800D01*
G01X806366Y203866D02*
X801203Y207481D01*
G01X790744Y210646D02*
X801713Y208712D01*
G01X801203Y207481D02*
X790234Y209415D01*
G01X801203Y207481D02*
X790234Y209415D01*
G01X790744Y210646D02*
X801713Y208712D01*
G01X806366Y203866D02*
X801203Y207481D01*
G01X801713Y208712D02*
X807300Y204800D01*
G01X798413Y214345D02*
X810153Y206125D01*
G01X798413Y214345D02*
X810153Y206125D01*
G01X787203Y191920D02*
X812477Y186549D01*
G01X786674Y190703D02*
X811971Y185327D01*
G01X773951Y201200D02*
X787203Y191920D01*
G01X773017Y200266D02*
X786674Y190703D01*
G01D02*
X811971Y185327D01*
G01X787203Y191920D02*
X812477Y186549D01*
G01X773017Y200266D02*
X786674Y190703D01*
G01X773951Y201200D02*
X787203Y191920D01*
G01X801200Y198827D02*
Y197760D01*
G01X799900Y198173D02*
Y198828D01*
G01X800300Y201000D02*
G02X801200Y198827I-2173J-2173D01*
G01X799899D02*
G03X799380Y200080I-1772J0D01*
G01X796744Y204556D02*
X800300Y201000D01*
G01X799380Y200081D02*
X796205Y203256D01*
G01X792401Y204556D02*
X796744D01*
G01X796205Y203256D02*
X791991D01*
G01X796205D02*
X791991D01*
G01X792401Y204556D02*
X796744D01*
G01X799380Y200081D02*
X796205Y203256D01*
G01X796744Y204556D02*
X800300Y201000D01*
G01X799899Y198827D02*
G03X799380Y200080I-1772J0D01*
G01X800300Y201000D02*
G02X801200Y198827I-2173J-2173D01*
G01X799900Y198173D02*
Y198828D01*
G01X801200Y198827D02*
Y197760D01*
G01X789200Y199213D02*
Y197800D01*
G01X790500Y197600D02*
Y199213D01*
G01X788949Y199675D02*
G02X789200Y199213I-300J-462D01*
G01X790500D02*
G03X789658Y200765I-1851J0D01*
G01X790500Y199213D02*
G03X789658Y200765I-1851J0D01*
G01X788949Y199675D02*
G02X789200Y199213I-300J-462D01*
G01X790500Y197600D02*
Y199213D01*
G01X789200D02*
Y197800D01*
G01X774655Y221912D02*
X790744Y210646D01*
G01X790234Y209415D02*
X773722Y220978D01*
G01X790234Y209415D02*
X773722Y220978D01*
G01X774655Y221912D02*
X790744Y210646D01*
G01X798942Y215562D02*
X811086Y207060D01*
G01X788266Y217831D02*
X798942Y215562D01*
G01X787760Y216609D02*
X798413Y214345D01*
G01X777724Y224677D02*
X788266Y217831D01*
G01X776784Y223737D02*
X787760Y216609D01*
G01X774678Y229366D02*
X777724Y224677D01*
G01X773442Y228882D02*
X776784Y223737D01*
G01X773023Y238937D02*
X774678Y229366D01*
G01X777009Y261551D02*
X773023Y238937D01*
G01X798942Y215562D02*
X811086Y207060D01*
G01X787760Y216609D02*
X798413Y214345D01*
G01X788266Y217831D02*
X798942Y215562D01*
G01X776784Y223737D02*
X787760Y216609D01*
G01X777724Y224677D02*
X788266Y217831D01*
G01X773442Y228882D02*
X776784Y223737D01*
G01X774678Y229366D02*
X777724Y224677D01*
G01X773023Y238937D02*
X774678Y229366D01*
G01X777009Y261551D02*
X773023Y238937D01*
G01X805897Y256405D02*
X809275Y275569D01*
G01X804576Y256405D02*
X807954Y275569D01*
G01X810990Y227519D02*
X805897Y256405D01*
G01X806278Y246746D02*
X804576Y256405D01*
G01D02*
X807954Y275569D01*
G01X805897Y256405D02*
X809275Y275569D01*
G01X806278Y246746D02*
X804576Y256405D01*
G01X810990Y227519D02*
X805897Y256405D01*
G01X810990Y227519D02*
X805897Y256405D01*
G01X810990Y227519D02*
X805897Y256405D01*
G01X809275Y275569D02*
X804721Y301404D01*
G01X807954Y275569D02*
X803490Y300894D01*
G01X807954Y275569D02*
X803490Y300894D01*
G01X809275Y275569D02*
X804721Y301404D01*
G01X792791Y660679D02*
X937001Y454735D01*
G01X794022Y661189D02*
X938232Y455245D01*
G01X794022Y661189D02*
X938232Y455245D01*
G01X792791Y660679D02*
X937001Y454735D01*
G01X933353Y452599D02*
X787795Y660476D01*
G01X934584Y453109D02*
X789026Y660986D01*
G01X934584Y453109D02*
X789026Y660986D01*
G01X933353Y452599D02*
X787795Y660476D01*
G01X925461Y446171D02*
X773915Y662604D01*
G01X926692Y446681D02*
X775146Y663114D01*
G01X928857Y451078D02*
X777463Y667290D01*
G01X930088Y451588D02*
X778694Y667800D01*
G01X926692Y446681D02*
X775146Y663114D01*
G01X925461Y446171D02*
X773915Y662604D01*
G01X930088Y451588D02*
X778694Y667800D01*
G01X928857Y451078D02*
X777463Y667290D01*
G01X782593Y810844D02*
X810673Y651597D01*
G01X782593Y810844D02*
X810673Y651597D01*
G01X939528Y460187D02*
X796982Y663765D01*
G01X940759Y460697D02*
X798213Y664275D01*
G01X940759Y460697D02*
X798213Y664275D01*
G01X939528Y460187D02*
X796982Y663765D01*
G01X783914Y810844D02*
X811904Y652107D01*
G01X789630Y800037D02*
X815788Y651689D01*
G01X790940Y800095D02*
X817019Y652199D01*
G01X783914Y810844D02*
X811904Y652107D01*
G01X790940Y800095D02*
X817019Y652199D01*
G01X789630Y800037D02*
X815788Y651689D01*
G01X799268Y775867D02*
X820300Y656570D01*
G01X800589Y775867D02*
X821531Y657080D01*
G01X800589Y775867D02*
X821531Y657080D01*
G01X799268Y775867D02*
X820300Y656570D01*
G01X807700Y823684D02*
X799268Y775867D01*
G01X809000Y823570D02*
X800589Y775867D01*
G01X809000Y823570D02*
X800589Y775867D01*
G01X807700Y823684D02*
X799268Y775867D01*
G01X783679Y817000D02*
X782593Y810844D01*
G01X785000Y817000D02*
X783914Y810844D01*
G01X789640Y800723D02*
Y800048D01*
G01X790940Y800609D02*
Y800095D01*
G01X793286Y821412D02*
X789640Y800723D01*
G01X794517Y820902D02*
X790940Y800609D01*
G01X785000Y817000D02*
X783914Y810844D01*
G01X783679Y817000D02*
X782593Y810844D01*
G01X790940Y800609D02*
Y800095D01*
G01X789640Y800723D02*
Y800048D01*
G01X794517Y820902D02*
X790940Y800609D01*
G01X793286Y821412D02*
X789640Y800723D01*
G01X782258Y825061D02*
X783679Y817000D01*
G01X783558Y825175D02*
X785000Y817000D01*
G01X782258Y840628D02*
Y825061D01*
G01X783558Y840742D02*
Y825175D01*
G01X781099Y847195D02*
X782258Y840628D01*
G01X782330Y847705D02*
X783558Y840742D01*
G01X774330Y856862D02*
X781099Y847195D01*
G01X775264Y857796D02*
X782330Y847705D01*
G01X795057Y823940D02*
X793286Y821412D01*
G01X796357Y823530D02*
X794517Y820902D01*
G01X795057Y840686D02*
Y823940D01*
G01X796357Y840800D02*
Y823530D01*
G01X794304Y844949D02*
X795057Y840686D01*
G01X795535Y845459D02*
X796357Y840800D01*
G01X785022Y858206D02*
X794304Y844949D01*
G01X785956Y859140D02*
X795535Y845459D01*
G01X783558Y825175D02*
X785000Y817000D01*
G01X782258Y825061D02*
X783679Y817000D01*
G01X783558Y840742D02*
Y825175D01*
G01X782258Y840628D02*
Y825061D01*
G01X782330Y847705D02*
X783558Y840742D01*
G01X781099Y847195D02*
X782258Y840628D01*
G01X775264Y857796D02*
X782330Y847705D01*
G01X774330Y856862D02*
X781099Y847195D01*
G01X796357Y823530D02*
X794517Y820902D01*
G01X795057Y823940D02*
X793286Y821412D01*
G01X796357Y840800D02*
Y823530D01*
G01X795057Y840686D02*
Y823940D01*
G01X795535Y845459D02*
X796357Y840800D01*
G01X794304Y844949D02*
X795057Y840686D01*
G01X785956Y859140D02*
X795535Y845459D01*
G01X785022Y858206D02*
X794304Y844949D01*
G01X798347Y865152D02*
X812058Y855551D01*
G01X799281Y866086D02*
X812992Y856485D01*
G01X795020Y869904D02*
X798347Y865152D01*
G01X796320Y870314D02*
X799281Y866086D01*
G01X795020Y872882D02*
Y869904D01*
G01X796320Y872882D02*
Y870314D01*
G01X799281Y866086D02*
X812992Y856485D01*
G01X798347Y865152D02*
X812058Y855551D01*
G01X796320Y870314D02*
X799281Y866086D01*
G01X795020Y869904D02*
X798347Y865152D01*
G01X796320Y872882D02*
Y870314D01*
G01X795020Y872882D02*
Y869904D01*
G01X805940Y850861D02*
X807700Y840886D01*
G01X802835Y855295D02*
X805940Y850861D01*
G01X803769Y856229D02*
X807171Y851371D01*
G01X784793Y867928D02*
X802835Y855295D01*
G01X785727Y868862D02*
X803769Y856229D01*
G01X782421Y871317D02*
X784793Y867928D01*
G01X783721Y871727D02*
X785727Y868862D01*
G01X782421Y872882D02*
Y871317D01*
G01X783721Y872882D02*
Y871727D01*
G01X805940Y850861D02*
X807700Y840886D01*
G01X803769Y856229D02*
X807171Y851371D01*
G01X802835Y855295D02*
X805940Y850861D01*
G01X785727Y868862D02*
X803769Y856229D01*
G01X784793Y867928D02*
X802835Y855295D01*
G01X783721Y871727D02*
X785727Y868862D01*
G01X782421Y871317D02*
X784793Y867928D01*
G01X783721Y872882D02*
Y871727D01*
G01X782421Y872882D02*
Y871317D01*
G01X772835Y866739D02*
X785022Y858206D01*
G01X773769Y867673D02*
X785956Y859140D01*
G01X773769Y867673D02*
X785956Y859140D01*
G01X772835Y866739D02*
X785022Y858206D01*
G01X835790Y89518D02*
X842947Y82361D01*
G01X834983Y88485D02*
X842124Y81344D01*
G01X828081Y94143D02*
X835790Y89518D01*
G01X827598Y92916D02*
X834983Y88485D01*
G01X824729Y94858D02*
X828081Y94143D01*
G01X824729Y93528D02*
X827598Y92916D01*
G01X815333Y92861D02*
X824729Y94858D01*
G01X815333Y91531D02*
X824729Y93528D01*
G01X813612Y93227D02*
X815333Y92861D01*
G01X815063Y91589D02*
X815333Y91531D01*
G01X813612Y91897D02*
X815063Y91589D01*
G01X823138Y107714D02*
X842372Y94248D01*
G01X822628Y106483D02*
X841862Y93017D01*
G01X819027Y108440D02*
X823138Y107714D01*
G01X819027Y107119D02*
X822628Y106483D01*
G01X809764Y106811D02*
X819027Y108440D01*
G01X809741Y105486D02*
X819027Y107119D01*
G01X834983Y88485D02*
X842124Y81344D01*
G01X835790Y89518D02*
X842947Y82361D01*
G01X827598Y92916D02*
X834983Y88485D01*
G01X828081Y94143D02*
X835790Y89518D01*
G01X824729Y93528D02*
X827598Y92916D01*
G01X824729Y94858D02*
X828081Y94143D01*
G01X815333Y91531D02*
X824729Y93528D01*
G01X815333Y92861D02*
X824729Y94858D01*
G01X815063Y91589D02*
X815333Y91531D01*
G01X813612Y93227D02*
X815333Y92861D01*
G01X813612Y91897D02*
X815063Y91589D01*
G01X813612Y93227D02*
X815333Y92861D01*
G01X822628Y106483D02*
X841862Y93017D01*
G01X823138Y107714D02*
X842372Y94248D01*
G01X819027Y107119D02*
X822628Y106483D01*
G01X819027Y108440D02*
X823138Y107714D01*
G01X809741Y105486D02*
X819027Y107119D01*
G01X809764Y106811D02*
X819027Y108440D01*
G01X824008Y111395D02*
X843142Y97999D01*
G01X823498Y110164D02*
X842632Y96768D01*
G01X832338Y96950D02*
X843366Y89790D01*
G01X820805Y102889D02*
X842879Y88555D01*
G01X821311Y104111D02*
X832338Y96950D01*
G01X820805Y102889D02*
X842879Y88555D01*
G01X819753Y104442D02*
X821311Y104111D01*
G01X817484Y103594D02*
X820805Y102889D01*
G01X817484Y104924D02*
X819753Y104442D01*
G01X817484Y103594D02*
X820805Y102889D01*
G01X812893Y103947D02*
X817484Y104924D01*
G01X813690Y102787D02*
X817484Y103594D01*
G01X809806Y99191D02*
X812893Y103947D01*
G01X810603Y98031D02*
X813690Y102787D01*
G01X823498Y110164D02*
X842632Y96768D01*
G01X824008Y111395D02*
X843142Y97999D01*
G01X820805Y102889D02*
X842879Y88555D01*
G01X832338Y96950D02*
X843366Y89790D01*
G01X821311Y104111D02*
X832338Y96950D01*
G01X817484Y103594D02*
X820805Y102889D01*
G01X819753Y104442D02*
X821311Y104111D01*
G01X817484Y104924D02*
X819753Y104442D01*
G01X813690Y102787D02*
X817484Y103594D01*
G01X812893Y103947D02*
X817484Y104924D01*
G01X810603Y98031D02*
X813690Y102787D01*
G01X809806Y99191D02*
X812893Y103947D01*
G01X844978Y101881D02*
X826404Y114884D01*
G01X844468Y100650D02*
X825894Y113653D01*
G01X844468Y100650D02*
X825894Y113653D01*
G01X844978Y101881D02*
X826404Y114884D01*
G01X806235Y114527D02*
X824008Y111395D01*
G01X806258Y113202D02*
X823498Y110164D01*
G01X806258Y113202D02*
X823498Y110164D01*
G01X806235Y114527D02*
X824008Y111395D01*
G01X831616Y120240D02*
X845473Y110537D01*
G01X831106Y119009D02*
X844962Y109307D01*
G01X832468Y123601D02*
X844560Y115134D01*
G01X831958Y122370D02*
X844047Y113906D01*
G01X828961Y117532D02*
X845188Y106165D01*
G01X828451Y116301D02*
X844678Y104934D01*
G01X831106Y119009D02*
X844962Y109307D01*
G01X831616Y120240D02*
X845473Y110537D01*
G01X831958Y122370D02*
X844047Y113906D01*
G01X832468Y123601D02*
X844560Y115134D01*
G01X828451Y116301D02*
X844678Y104934D01*
G01X828961Y117532D02*
X845188Y106165D01*
G01X839474Y125097D02*
X863244Y129290D01*
G01X839474Y126418D02*
X863016Y130571D01*
G01X838494Y134451D02*
X861077Y138432D01*
G01X838494Y133130D02*
X861302Y137151D01*
G01X837335Y138349D02*
X860136Y142369D01*
G01X860253Y141069D02*
X837335Y137028D01*
G01X839474Y126418D02*
X863016Y130571D01*
G01X839474Y125097D02*
X863244Y129290D01*
G01X838494Y133130D02*
X861302Y137151D01*
G01X838494Y134451D02*
X861077Y138432D01*
G01X860253Y141069D02*
X837335Y137028D01*
G01Y138349D02*
X860136Y142369D01*
G01X838813Y129084D02*
X862539Y133269D01*
G01X838813Y130405D02*
X862425Y134569D01*
G01X859497Y145038D02*
X837888Y141227D01*
G01X838813Y130405D02*
X862425Y134569D01*
G01X838813Y129084D02*
X862539Y133269D01*
G01X859497Y145038D02*
X837888Y141227D01*
G01X842476Y164751D02*
X821073Y169300D01*
G01X836535Y167343D02*
X838149Y167000D01*
G01X842476Y164751D02*
X821073Y169300D01*
G01X831937Y168320D02*
X833551Y167977D01*
G01X842476Y164751D02*
X821073Y169300D01*
G01X827340Y169298D02*
X828954Y168955D01*
G01X842476Y164751D02*
X821073Y169300D01*
G01X821579Y170522D02*
X824357Y169932D01*
G01X842476Y164751D02*
X821073Y169300D01*
G01X842476Y164751D02*
X821073Y169300D01*
G01X836535Y167343D02*
X838149Y167000D01*
G01X831937Y168320D02*
X833551Y167977D01*
G01X827340Y169298D02*
X828954Y168955D01*
G01X821579Y170522D02*
X824357Y169932D01*
G01X859383Y146338D02*
X837888Y142548D01*
G01X857430Y154199D02*
X837801Y150738D01*
G01X857544Y152899D02*
X837779Y149413D01*
G01X859383Y146338D02*
X837888Y142548D01*
G01X857544Y152899D02*
X837779Y149413D01*
G01X857430Y154199D02*
X837801Y150738D01*
G01X856232Y158117D02*
X837276Y154776D01*
G01X856346Y156817D02*
X837254Y153451D01*
G01X839804Y144995D02*
X858387Y148945D01*
G01X839804Y146325D02*
X858250Y150245D01*
G01X829968Y147086D02*
X839804Y144995D01*
G01X830238Y148358D02*
X839804Y146325D01*
G01X856346Y156817D02*
X837254Y153451D01*
G01X856232Y158117D02*
X837276Y154776D01*
G01X839804Y146325D02*
X858250Y150245D01*
G01X839804Y144995D02*
X858387Y148945D01*
G01X830238Y148358D02*
X839804Y146325D01*
G01X829968Y147086D02*
X839804Y144995D01*
G01X830450Y174876D02*
X858382Y169950D01*
G01X829963Y173641D02*
X858157Y168669D01*
G01X812477Y186549D02*
X830450Y174876D01*
G01X811971Y185327D02*
X829963Y173641D01*
G01D02*
X858157Y168669D01*
G01X830450Y174876D02*
X858382Y169950D01*
G01X811971Y185327D02*
X829963Y173641D01*
G01X812477Y186549D02*
X830450Y174876D01*
G01X834182Y178406D02*
X860303Y173800D01*
G01X860185Y172500D02*
X833672Y177175D01*
G01X817700Y189947D02*
X834182Y178406D01*
G01X833672Y177175D02*
X816766Y189013D01*
G01X807300Y204800D02*
X817700Y189947D01*
G01X816635Y189201D02*
X806366Y203866D01*
G01X816766Y189013D02*
X816634Y189201D01*
G01X816635D02*
X806366Y203866D01*
G01X807300Y204800D02*
X817700Y189947D01*
G01X816766Y189013D02*
X816634Y189201D01*
G01X807300Y204800D02*
X817700Y189947D01*
G01X833672Y177175D02*
X816766Y189013D01*
G01X817700Y189947D02*
X834182Y178406D01*
G01X860185Y172500D02*
X833672Y177175D01*
G01X834182Y178406D02*
X860303Y173800D01*
G01X837987Y207941D02*
X829928Y219450D01*
G01X837053Y207007D02*
X828697Y218940D01*
G01X856998Y194629D02*
X837987Y207941D01*
G01X856488Y193398D02*
X837053Y207007D01*
G01D02*
X828697Y218940D01*
G01X837987Y207941D02*
X829928Y219450D01*
G01X856488Y193398D02*
X837053Y207007D01*
G01X856998Y194629D02*
X837987Y207941D01*
G01X836058Y199437D02*
X816245Y227736D01*
G01X836992Y200371D02*
X817476Y228246D01*
G01X851443Y188664D02*
X836058Y199437D01*
G01X851953Y189895D02*
X836992Y200371D01*
G01X832105Y197365D02*
X810990Y227519D01*
G01X831171Y196431D02*
X809759Y227009D01*
G01X851854Y183537D02*
X832105Y197365D01*
G01X851344Y182306D02*
X831171Y196431D01*
G01X836992Y200371D02*
X817476Y228246D01*
G01X836058Y199437D02*
X816245Y227736D01*
G01X851953Y189895D02*
X836992Y200371D01*
G01X851443Y188664D02*
X836058Y199437D01*
G01X835953Y182161D02*
X861497Y177657D01*
G01X835443Y180930D02*
X861383Y176357D01*
G01X821466Y192305D02*
X835953Y182161D01*
G01X820533Y191370D02*
X835443Y180930D01*
G01X811086Y207060D02*
X821466Y192305D01*
G01X810153Y206125D02*
X820533Y191370D01*
G01X831171Y196431D02*
X809759Y227009D01*
G01X832105Y197365D02*
X810990Y227519D01*
G01X851344Y182306D02*
X831171Y196431D01*
G01X851854Y183537D02*
X832105Y197365D01*
G01X835443Y180930D02*
X861383Y176357D01*
G01X835953Y182161D02*
X861497Y177657D01*
G01X820533Y191370D02*
X835443Y180930D01*
G01X821466Y192305D02*
X835953Y182161D01*
G01X810153Y206125D02*
X820533Y191370D01*
G01X811086Y207060D02*
X821466Y192305D01*
G01X833015Y220712D02*
X828891Y244097D01*
G01X830212D02*
X834246Y221222D01*
G01X839908Y210868D02*
X833015Y220712D01*
G01X834246Y221222D02*
X840842Y211802D01*
G01X859249Y197326D02*
X839908Y210868D01*
G01X837891Y225278D02*
X834736Y243164D01*
G01X839122Y225788D02*
X836057Y243164D01*
G01X847229Y211942D02*
X837891Y225278D01*
G01X848163Y212876D02*
X839122Y225788D01*
G01X859249Y197326D02*
X839908Y210868D01*
G01X834246Y221222D02*
X840842Y211802D01*
G01X839908Y210868D02*
X833015Y220712D01*
G01X830212Y244097D02*
X834246Y221222D01*
G01X833015Y220712D02*
X828891Y244097D01*
G01X839122Y225788D02*
X836057Y243164D01*
G01X837891Y225278D02*
X834736Y243164D01*
G01X848163Y212876D02*
X839122Y225788D01*
G01X847229Y211942D02*
X837891Y225278D01*
G01X829928Y219450D02*
X825390Y245187D01*
G01X828697Y218940D02*
X824069Y245187D01*
G01X828697Y218940D02*
X824069Y245187D01*
G01X829928Y219450D02*
X825390Y245187D01*
G01X816245Y227736D02*
X810208Y261959D01*
G01X817476Y228246D02*
X811529Y261959D01*
G01X807162Y241736D02*
X806278Y246746D01*
G01X809759Y227009D02*
X807162Y241736D01*
G01X817476Y228246D02*
X811529Y261959D01*
G01X816245Y227736D02*
X810208Y261959D01*
G01X807162Y241736D02*
X806278Y246746D01*
G01X809759Y227009D02*
X807162Y241736D01*
G01X833245Y268787D02*
X831144Y280695D01*
G01X832465D02*
X834566Y268787D01*
G01X828891Y244097D02*
X833245Y268787D01*
G01X834566D02*
X830212Y244097D01*
G01X838921Y266898D02*
X836522Y280507D01*
G01X840242Y266898D02*
X837822Y280621D01*
G01X834736Y243164D02*
X838921Y266898D01*
G01X836057Y243164D02*
X840242Y266898D01*
G01X834566Y268787D02*
X830212Y244097D01*
G01X828891D02*
X833245Y268787D01*
G01X832465Y280695D02*
X834566Y268787D01*
G01X833245D02*
X831144Y280695D01*
G01X840242Y266898D02*
X837822Y280621D01*
G01X838921Y266898D02*
X836522Y280507D01*
G01X836057Y243164D02*
X840242Y266898D01*
G01X834736Y243164D02*
X838921Y266898D01*
G01X830509Y274219D02*
X825923Y300188D01*
G01X829188Y274219D02*
X824692Y299678D01*
G01X825390Y245187D02*
X830509Y274219D01*
G01X824069Y245187D02*
X829188Y274219D01*
G01D02*
X824692Y299678D01*
G01X830509Y274219D02*
X825923Y300188D01*
G01X824069Y245187D02*
X829188Y274219D01*
G01X825390Y245187D02*
X830509Y274219D01*
G01X810208Y261959D02*
X812809Y276713D01*
G01X811529Y261959D02*
X814130Y276713D01*
G01X811529Y261959D02*
X814130Y276713D01*
G01X810208Y261959D02*
X812809Y276713D01*
G01X833387Y293415D02*
X832369Y299190D01*
G01X833600Y299700D02*
X834708Y293415D01*
G01X831144Y280695D02*
X833387Y293415D01*
G01X834708D02*
X832465Y280695D01*
G01X838689Y294785D02*
X836282Y308433D01*
G01X839989Y294899D02*
X837513Y308943D01*
G01X838689Y293049D02*
Y294785D01*
G01X836539Y280859D02*
X838689Y293049D01*
G01X837822Y280648D02*
X839989Y292935D01*
G01X836522Y280751D02*
X836539Y280859D01*
G01X837822Y280648D02*
X839989Y292935D01*
G01X834708Y293415D02*
X832465Y280695D01*
G01X831144D02*
X833387Y293415D01*
G01X833600Y299700D02*
X834708Y293415D01*
G01X833387D02*
X832369Y299190D01*
G01X839989Y294899D02*
X837513Y308943D01*
G01X838689Y294785D02*
X836282Y308433D01*
G01X838689Y293049D02*
Y294785D01*
G01X837822Y280648D02*
X839989Y292935D01*
G01X836539Y280859D02*
X838689Y293049D01*
G01X836522Y280751D02*
X836539Y280859D01*
G01X812809Y276713D02*
X807427Y307228D01*
G01X814130Y276713D02*
X808658Y307738D01*
G01X814130Y276713D02*
X808658Y307738D01*
G01X812809Y276713D02*
X807427Y307228D01*
G01X839853Y310520D02*
X843339Y290751D01*
G01X839853Y310520D02*
X843339Y290751D01*
G01X810673Y651597D02*
X943981Y461213D01*
G01X811904Y652107D02*
X945212Y461723D01*
G01X811904Y652107D02*
X945212Y461723D01*
G01X810673Y651597D02*
X943981Y461213D01*
G01X825089Y661113D02*
X958225Y470973D01*
G01X826320Y661623D02*
X959456Y471483D01*
G01X826320Y661623D02*
X959456Y471483D01*
G01X825089Y661113D02*
X958225Y470973D01*
G01X820300Y656570D02*
X955431Y463577D01*
G01X821531Y657080D02*
X956662Y464087D01*
G01X821531Y657080D02*
X956662Y464087D01*
G01X820300Y656570D02*
X955431Y463577D01*
G01X815788Y651689D02*
X949392Y460884D01*
G01X817019Y652199D02*
X950623Y461394D01*
G01X817019Y652199D02*
X950623Y461394D01*
G01X815788Y651689D02*
X949392Y460884D01*
G01X828397Y665604D02*
X815210Y740388D01*
G01X829628Y666114D02*
X816531Y740388D01*
G01X960833Y476464D02*
X828397Y665604D01*
G01X962064Y476974D02*
X829628Y666114D01*
G01X833220Y667713D02*
X964713Y479920D01*
G01X834451Y668223D02*
X965944Y480430D01*
G01X820552Y739554D02*
X833220Y667713D01*
G01X821873Y739554D02*
X834451Y668223D01*
G01X837893Y670922D02*
X826245Y736983D01*
G01X827566D02*
X839124Y671432D01*
G01X968863Y483879D02*
X837893Y670922D01*
G01X839124Y671432D02*
X970094Y484389D01*
G01X829628Y666114D02*
X816531Y740388D01*
G01X828397Y665604D02*
X815210Y740388D01*
G01X962064Y476974D02*
X829628Y666114D01*
G01X960833Y476464D02*
X828397Y665604D01*
G01X834451Y668223D02*
X965944Y480430D01*
G01X833220Y667713D02*
X964713Y479920D01*
G01X821873Y739554D02*
X834451Y668223D01*
G01X820552Y739554D02*
X833220Y667713D01*
G01X839124Y671432D02*
X970094Y484389D01*
G01X968863Y483879D02*
X837893Y670922D01*
G01X827566Y736983D02*
X839124Y671432D01*
G01X837893Y670922D02*
X826245Y736983D01*
G01X811179Y740000D02*
X825089Y661113D01*
G01X812500Y740000D02*
X826320Y661623D01*
G01X812500Y740000D02*
X826320Y661623D01*
G01X811179Y740000D02*
X825089Y661113D01*
G01X815210Y740388D02*
X827770Y811621D01*
G01X816531Y740388D02*
X829091Y811621D01*
G01X833679Y814000D02*
X820552Y739554D01*
G01X835000Y814000D02*
X821873Y739554D01*
G01X826245Y736983D02*
X839186Y810379D01*
G01X840417Y809869D02*
X827566Y736983D01*
G01X816531Y740388D02*
X829091Y811621D01*
G01X815210Y740388D02*
X827770Y811621D01*
G01X835000Y814000D02*
X821873Y739554D01*
G01X833679Y814000D02*
X820552Y739554D01*
G01X840417Y809869D02*
X827566Y736983D01*
G01X826245D02*
X839186Y810379D01*
G01X823858Y811909D02*
X811179Y740000D01*
G01X825179Y811909D02*
X812500Y740000D01*
G01X825179Y811909D02*
X812500Y740000D01*
G01X823858Y811909D02*
X811179Y740000D01*
G01X827770Y811621D02*
X820998Y850024D01*
G01X829091Y811621D02*
X822229Y850534D01*
G01X830565Y831660D02*
X833679Y814000D01*
G01X831875Y831718D02*
X835000Y814000D01*
G01X839186Y810379D02*
X843986Y817234D01*
G01X829091Y811621D02*
X822229Y850534D01*
G01X827770Y811621D02*
X820998Y850024D01*
G01X831875Y831718D02*
X835000Y814000D01*
G01X830565Y831660D02*
X833679Y814000D01*
G01X839186Y810379D02*
X843986Y817234D01*
G01X817545Y847715D02*
X823858Y811909D01*
G01X818776Y848225D02*
X825179Y811909D01*
G01X818776Y848225D02*
X825179Y811909D01*
G01X817545Y847715D02*
X823858Y811909D01*
G01X820998Y850024D02*
X808305Y868150D01*
G01X830575Y832346D02*
Y831671D01*
G01X831875Y832232D02*
Y831718D01*
G01X834531Y854833D02*
X830575Y832346D01*
G01X835852Y854833D02*
X831875Y832232D01*
G01X820998Y850024D02*
X808305Y868150D01*
G01X831875Y832232D02*
Y831718D01*
G01X830575Y832346D02*
Y831671D01*
G01X835852Y854833D02*
X831875Y832232D01*
G01X834531Y854833D02*
X830575Y832346D01*
G01X812058Y855551D02*
X817545Y847715D01*
G01X812992Y856485D02*
X818776Y848225D01*
G01X812992Y856485D02*
X818776Y848225D01*
G01X812058Y855551D02*
X817545Y847715D01*
G01X807700Y840886D02*
Y823684D01*
G01X809000Y841000D02*
Y823570D01*
G01X807171Y851371D02*
X809000Y841000D01*
G01D02*
Y823570D01*
G01X807700Y840886D02*
Y823684D01*
G01X807171Y851371D02*
X809000Y841000D01*
G01X807618Y870329D02*
Y872882D01*
G01X808918Y870331D02*
Y872882D01*
G01X808305Y868150D02*
G02X807618Y870329I3113J2179D01*
G01X809370Y868897D02*
G02X808918Y870331I2048J1434D01*
G01X822229Y850534D02*
X809370Y868897D01*
G01X832815Y864565D02*
X834531Y854833D01*
G01X834115Y864682D02*
X835852Y854833D01*
G01X832815Y872882D02*
Y864565D01*
G01X834115Y872882D02*
Y864682D01*
G01X808918Y870331D02*
Y872882D01*
G01X807618Y870329D02*
Y872882D01*
G01X809370Y868897D02*
G02X808918Y870331I2048J1434D01*
G01X808305Y868150D02*
G02X807618Y870329I3113J2179D01*
G01X822229Y850534D02*
X809370Y868897D01*
G01X834115Y864682D02*
X835852Y854833D01*
G01X832815Y864565D02*
X834531Y854833D01*
G01X834115Y872882D02*
Y864682D01*
G01X832815Y872882D02*
Y864565D01*
G01X863949Y73953D02*
X879562Y71200D01*
G01X863439Y72722D02*
X879562Y69879D01*
G01X856792Y78963D02*
X863949Y73953D01*
G01X856282Y77732D02*
X863439Y72722D01*
G01D02*
X879562Y69879D01*
G01X863949Y73953D02*
X879562Y71200D01*
G01X856282Y77732D02*
X863439Y72722D01*
G01X856792Y78963D02*
X863949Y73953D01*
G01X844975Y81045D02*
X856792Y78963D01*
G01X844489Y79810D02*
X856282Y77732D01*
G01X842947Y82361D02*
X844975Y81045D01*
G01X842124Y81344D02*
X844489Y79810D01*
G01X867434Y81882D02*
X879618Y79445D01*
G01X866911Y80660D02*
X879603Y78122D01*
G01X852263Y92504D02*
X867434Y81882D01*
G01X851753Y91273D02*
X866911Y80660D01*
G01X842372Y94248D02*
X852263Y92504D01*
G01X841862Y93017D02*
X851753Y91273D01*
G01X844489Y79810D02*
X856282Y77732D01*
G01X844975Y81045D02*
X856792Y78963D01*
G01X842124Y81344D02*
X844489Y79810D01*
G01X842947Y82361D02*
X844975Y81045D01*
G01X866911Y80660D02*
X879603Y78122D01*
G01X867434Y81882D02*
X879618Y79445D01*
G01X851753Y91273D02*
X866911Y80660D01*
G01X852263Y92504D02*
X867434Y81882D01*
G01X841862Y93017D02*
X851753Y91273D01*
G01X842372Y94248D02*
X852263Y92504D01*
G01X867630Y93680D02*
X889209Y89364D01*
G01X867375Y92405D02*
X889209Y88038D01*
G01X867600Y93686D02*
X867624D01*
G01X867375Y92405D02*
X889209Y88038D01*
G01X842632Y96768D02*
X867375Y92405D01*
G01X843142Y97999D02*
X867600Y93686D01*
G01X842632Y96768D02*
X867375Y92405D01*
G01X867355Y77971D02*
X880530Y75335D01*
G01X866832Y76749D02*
X880538Y74007D01*
G01X852870Y88114D02*
X867355Y77971D01*
G01X852360Y86883D02*
X866832Y76749D01*
G01X843366Y89790D02*
X852870Y88114D01*
G01X842879Y88555D02*
X852360Y86883D01*
G01X867375Y92405D02*
X889209Y88038D01*
G01X867630Y93680D02*
X889209Y89364D01*
G01X867600Y93686D02*
X867624D01*
G01X842632Y96768D02*
X867375Y92405D01*
G01X867600Y93686D02*
X867624D01*
G01X843142Y97999D02*
X867600Y93686D01*
G01X866832Y76749D02*
X880538Y74007D01*
G01X867355Y77971D02*
X880530Y75335D01*
G01X852360Y86883D02*
X866832Y76749D01*
G01X852870Y88114D02*
X867355Y77971D01*
G01X842879Y88555D02*
X852360Y86883D01*
G01X843366Y89790D02*
X852870Y88114D01*
G01X875825Y96442D02*
X844978Y101881D01*
G01X875585Y95164D02*
X844468Y100650D01*
G01X873534Y105538D02*
X888813Y108232D01*
G01X873533Y104217D02*
X888813Y106911D01*
G01X845473Y110537D02*
X873534Y105538D01*
G01X844962Y109307D02*
X873533Y104217D01*
G01X872310Y101383D02*
X888140Y104174D01*
G01X872310Y100062D02*
X888140Y102853D01*
G01X845188Y106165D02*
X872310Y101383D01*
G01X844678Y104934D02*
X872310Y100062D01*
G01X875585Y95164D02*
X844468Y100650D01*
G01X875825Y96442D02*
X844978Y101881D01*
G01X873533Y104217D02*
X888813Y106911D01*
G01X873534Y105538D02*
X888813Y108232D01*
G01X844962Y109307D02*
X873533Y104217D01*
G01X845473Y110537D02*
X873534Y105538D01*
G01X872310Y100062D02*
X888140Y102853D01*
G01X872310Y101383D02*
X888140Y104174D01*
G01X844678Y104934D02*
X872310Y100062D01*
G01X845188Y106165D02*
X872310Y101383D01*
G01X844560Y115134D02*
X874766Y109637D01*
G01X844047Y113906D02*
X874762Y108316D01*
G01X844047Y113906D02*
X874762Y108316D01*
G01X844560Y115134D02*
X874766Y109637D01*
G01X863244Y129290D02*
X871338D01*
G01X863035Y130590D02*
X871338D01*
G01X861096Y138451D02*
X871480D01*
G01X861302Y137151D02*
X871480D01*
G01X871274Y141069D02*
X860253D01*
G01X863035Y130590D02*
X871338D01*
G01X863244Y129290D02*
X871338D01*
G01X861302Y137151D02*
X871480D01*
G01X861096Y138451D02*
X871480D01*
G01X871274Y141069D02*
X860253D01*
G01X862539Y133269D02*
X871047D01*
G01X862425Y134569D02*
X871059D01*
G01X862425D02*
X871059D01*
G01X862539Y133269D02*
X871047D01*
G01X842746Y166023D02*
X872457D01*
G01Y164723D02*
X842504D01*
G01X841132Y166366D02*
X842746Y166023D01*
G01X841132Y166366D02*
X842746Y166023D01*
G01X872457Y164723D02*
X842504D01*
G01X842746Y166023D02*
X872457D01*
G01X860136Y142369D02*
X871274D01*
G01X860136D02*
X871274D01*
G01X870539Y145038D02*
X859497D01*
G01X870539Y146338D02*
X859383D01*
G01X868015Y154199D02*
X857430D01*
G01X868209Y152899D02*
X857544D01*
G01X870539Y146338D02*
X859383D01*
G01X870539Y145038D02*
X859497D01*
G01X868209Y152899D02*
X857544D01*
G01X868015Y154199D02*
X857430D01*
G01X868673Y158117D02*
X856232D01*
G01X868867Y156817D02*
X856346D01*
G01X858387Y148945D02*
X867971D01*
G01X858250Y150245D02*
X867971D01*
G01X868867Y156817D02*
X856346D01*
G01X868673Y158117D02*
X856232D01*
G01X858250Y150245D02*
X867971D01*
G01X858387Y148945D02*
X867971D01*
G01X860303Y173800D02*
X878300D01*
G01Y172500D02*
X860185D01*
G01X878300D02*
X860185D01*
G01X860303Y173800D02*
X878300D01*
G01X858382Y169950D02*
X877606D01*
G01X858176Y168650D02*
X877800D01*
G01X858176D02*
X877800D01*
G01X858382Y169950D02*
X877606D01*
G01X865686Y208000D02*
X873000D01*
G01X859032Y209172D02*
X865686Y208000D01*
G01X850313Y215277D02*
X859032Y209172D01*
G01X865686Y208000D02*
X873000D01*
G01X859032Y209172D02*
X865686Y208000D01*
G01X850313Y215277D02*
X859032Y209172D01*
G01X840842Y211802D02*
X859759Y198557D01*
G01X865636Y196200D02*
X859249Y197326D01*
G01X859759Y198557D02*
X865750Y197500D01*
G01X872606Y196200D02*
X865636D01*
G01X865750Y197500D02*
X872900D01*
G01X856729Y205290D02*
X847229Y211942D01*
G01X857239Y206521D02*
X848163Y212876D01*
G01X863486Y204100D02*
X856729Y205290D01*
G01X863600Y205400D02*
X857239Y206521D01*
G01X872100Y204100D02*
X863486D01*
G01X872100Y205400D02*
X863600D01*
G01X865750Y197500D02*
X872900D01*
G01X872606Y196200D02*
X865636D01*
G01X859759Y198557D02*
X865750Y197500D01*
G01X865636Y196200D02*
X859249Y197326D01*
G01X840842Y211802D02*
X859759Y198557D01*
G01X857239Y206521D02*
X848163Y212876D01*
G01X856729Y205290D02*
X847229Y211942D01*
G01X863600Y205400D02*
X857239Y206521D01*
G01X863486Y204100D02*
X856729Y205290D01*
G01X872100Y205400D02*
X863600D01*
G01X872100Y204100D02*
X863486D01*
G01X860936Y193935D02*
X856998Y194629D01*
G01X860711Y192654D02*
X856488Y193398D01*
G01X862272Y193700D02*
X860936Y193935D01*
G01X862158Y192400D02*
X860711Y192654D01*
G01X871800Y193700D02*
X862272D01*
G01X871444Y192400D02*
X862158D01*
G01X860711Y192654D02*
X856488Y193398D01*
G01X860936Y193935D02*
X856998Y194629D01*
G01X862158Y192400D02*
X860711Y192654D01*
G01X862272Y193700D02*
X860936Y193935D01*
G01X871444Y192400D02*
X862158D01*
G01X871800Y193700D02*
X862272D01*
G01X862587Y186700D02*
X851443Y188664D01*
G01X855965Y189188D02*
X851953Y189895D01*
G01X862706Y188000D02*
X855965Y189188D01*
G01X890770Y186700D02*
X862587D01*
G01X890769Y188000D02*
X862706D01*
G01X860571Y182000D02*
X851854Y183537D01*
G01X860457Y180700D02*
X851344Y182306D01*
G01X872400Y182000D02*
X860571D01*
G01X871861Y180700D02*
X860457D01*
G01X872954Y181446D02*
X872400Y182000D01*
G01X872415Y180146D02*
X871861Y180700D01*
G01X884000Y181446D02*
X872954D01*
G01X883900Y180146D02*
X872415D01*
G01X855965Y189188D02*
X851953Y189895D01*
G01X862587Y186700D02*
X851443Y188664D01*
G01X862706Y188000D02*
X855965Y189188D01*
G01X862587Y186700D02*
X851443Y188664D01*
G01X890769Y188000D02*
X862706D01*
G01X890770Y186700D02*
X862587D01*
G01X861497Y177657D02*
X871318D01*
G01X861383Y176357D02*
X871857D01*
G01X860457Y180700D02*
X851344Y182306D01*
G01X860571Y182000D02*
X851854Y183537D01*
G01X871861Y180700D02*
X860457D01*
G01X872400Y182000D02*
X860571D01*
G01X872415Y180146D02*
X871861Y180700D01*
G01X872954Y181446D02*
X872400Y182000D01*
G01X883900Y180146D02*
X872415D01*
G01X884000Y181446D02*
X872954D01*
G01X861383Y176357D02*
X871857D01*
G01X861497Y177657D02*
X871318D01*
G01X871718Y236982D02*
X875700Y233000D01*
G01X874780Y232081D02*
X870509Y236351D01*
G01X869791Y247905D02*
X871718Y236982D01*
G01X870509Y236351D02*
X868491Y247791D01*
G01X870509Y236351D02*
X868491Y247791D01*
G01X869791Y247905D02*
X871718Y236982D01*
G01X874780Y232081D02*
X870509Y236351D01*
G01X871718Y236982D02*
X875700Y233000D01*
G01X867019Y233480D02*
X871846Y228653D01*
G01X868229Y234110D02*
X873285Y229054D01*
G01X864793Y246108D02*
X867019Y233480D01*
G01X866093Y246222D02*
X868229Y234110D01*
G01X862013Y242914D02*
X865833Y264585D01*
G01X860692Y242914D02*
X864512Y264585D01*
G01X863615Y233825D02*
X862013Y242914D01*
G01X862405Y233195D02*
X860692Y242914D01*
G01X872240Y225200D02*
X863615Y233825D01*
G01X871700Y223900D02*
X862405Y233195D01*
G01X873300Y225200D02*
X872240D01*
G01X871700Y223900D02*
X862405Y233195D01*
G01X873300Y223900D02*
X871700D01*
G01X868229Y234110D02*
X873285Y229054D01*
G01X867019Y233480D02*
X871846Y228653D01*
G01X866093Y246222D02*
X868229Y234110D01*
G01X864793Y246108D02*
X867019Y233480D01*
G01X860692Y242914D02*
X864512Y264585D01*
G01X862013Y242914D02*
X865833Y264585D01*
G01X862405Y233195D02*
X860692Y242914D01*
G01X863615Y233825D02*
X862013Y242914D01*
G01X871700Y223900D02*
X862405Y233195D01*
G01X872240Y225200D02*
X863615Y233825D01*
G01X873300Y225200D02*
X872240D01*
G01X873300Y223900D02*
X871700D01*
G01X873300Y225200D02*
X872240D01*
G01X870827Y219800D02*
X871600D01*
G01X870941Y221100D02*
X872400D01*
G01X866512Y220560D02*
X870827Y219800D01*
G01X867022Y221791D02*
X870941Y221100D01*
G01X861344Y224179D02*
X866512Y220560D01*
G01X862278Y225113D02*
X867022Y221791D01*
G01X856644Y230891D02*
X861344Y224179D01*
G01X857875Y231401D02*
X862278Y225113D01*
G01X854268Y244362D02*
X856644Y230891D01*
G01X855589Y244362D02*
X857875Y231401D01*
G01X870941Y221100D02*
X872400D01*
G01X870827Y219800D02*
X871600D01*
G01X867022Y221791D02*
X870941Y221100D01*
G01X866512Y220560D02*
X870827Y219800D01*
G01X862278Y225113D02*
X867022Y221791D01*
G01X861344Y224179D02*
X866512Y220560D01*
G01X857875Y231401D02*
X862278Y225113D01*
G01X856644Y230891D02*
X861344Y224179D01*
G01X855589Y244362D02*
X857875Y231401D01*
G01X854268Y244362D02*
X856644Y230891D01*
G01X869186Y215800D02*
X873300D01*
G01X869300Y217100D02*
X873300D01*
G01X863953Y216722D02*
X869186Y215800D01*
G01X864463Y217953D02*
X869300Y217100D01*
G01X859371Y219931D02*
X863953Y216722D01*
G01X860305Y220865D02*
X864463Y217953D01*
G01X852759Y229374D02*
X859371Y219931D01*
G01X853990Y229884D02*
X860305Y220865D01*
G01X849989Y245076D02*
X852759Y229374D01*
G01X851310Y245076D02*
X853990Y229884D01*
G01X869300Y217100D02*
X873300D01*
G01X869186Y215800D02*
X873300D01*
G01X864463Y217953D02*
X869300Y217100D01*
G01X863953Y216722D02*
X869186Y215800D01*
G01X860305Y220865D02*
X864463Y217953D01*
G01X859371Y219931D02*
X863953Y216722D01*
G01X853990Y229884D02*
X860305Y220865D01*
G01X852759Y229374D02*
X859371Y219931D01*
G01X851310Y245076D02*
X853990Y229884D01*
G01X849989Y245076D02*
X852759Y229374D01*
G01X867386Y212000D02*
X872300D01*
G01X867500Y213300D02*
X872300D01*
G01X861423Y213051D02*
X867386Y212000D01*
G01X861933Y214282D02*
X867500Y213300D01*
G01X854868Y217641D02*
X861423Y213051D01*
G01X855802Y218575D02*
X861933Y214282D01*
G01X850160Y224365D02*
X854868Y217641D01*
G01X851391Y224875D02*
X855802Y218575D01*
G01X845700Y249656D02*
X850160Y224365D01*
G01X847021Y249656D02*
X851391Y224875D01*
G01X867500Y213300D02*
X872300D01*
G01X867386Y212000D02*
X872300D01*
G01X861933Y214282D02*
X867500Y213300D01*
G01X861423Y213051D02*
X867386Y212000D01*
G01X855802Y218575D02*
X861933Y214282D01*
G01X854868Y217641D02*
X861423Y213051D01*
G01X851391Y224875D02*
X855802Y218575D01*
G01X850160Y224365D02*
X854868Y217641D01*
G01X847021Y249656D02*
X851391Y224875D01*
G01X845700Y249656D02*
X850160Y224365D01*
G01X865800Y209300D02*
X873000D01*
G01X859542Y210403D02*
X865800Y209300D01*
G01X851247Y216211D02*
X859542Y210403D01*
G01X845795Y221729D02*
X850313Y215277D01*
G01X847026Y222239D02*
X851247Y216211D01*
G01X840649Y250915D02*
X845795Y221729D01*
G01X841970Y250915D02*
X847026Y222239D01*
G01X865800Y209300D02*
X873000D01*
G01X859542Y210403D02*
X865800Y209300D01*
G01X851247Y216211D02*
X859542Y210403D01*
G01X847026Y222239D02*
X851247Y216211D01*
G01X845795Y221729D02*
X850313Y215277D01*
G01X841970Y250915D02*
X847026Y222239D01*
G01X840649Y250915D02*
X845795Y221729D01*
G01X869791Y249531D02*
Y247905D01*
G01X868491Y247791D02*
Y249661D01*
G01X872736Y264259D02*
X869791Y249531D01*
G01X868491Y249661D02*
X871410Y264259D01*
G01X871439Y270751D02*
X872736Y264259D01*
G01X871410D02*
X870116Y270736D01*
G01X874471Y287956D02*
X871439Y270751D01*
G01X870116Y270736D02*
X873150Y287956D01*
G01X870116Y270736D02*
X873150Y287956D01*
G01X874471D02*
X871439Y270751D01*
G01X871410Y264259D02*
X870116Y270736D01*
G01X871439Y270751D02*
X872736Y264259D01*
G01X868491Y249661D02*
X871410Y264259D01*
G01X872736D02*
X869791Y249531D01*
G01X868491Y247791D02*
Y249661D01*
G01X869791Y249531D02*
Y247905D01*
G01X864793Y247988D02*
Y246108D01*
G01X866093Y247859D02*
Y246222D01*
G01X868044Y264259D02*
X864793Y247988D01*
G01X869370Y264259D02*
X866093Y247859D01*
G01X865743Y275764D02*
X868044Y264259D01*
G01X867065Y275785D02*
X869370Y264259D01*
G01X868078Y289704D02*
X865743Y275764D01*
G01X869398Y289710D02*
X867065Y275785D01*
G01X865833Y264585D02*
X863176Y279654D01*
G01X864512Y264585D02*
X861855Y279654D01*
G01X866093Y247859D02*
Y246222D01*
G01X864793Y247988D02*
Y246108D01*
G01X869370Y264259D02*
X866093Y247859D01*
G01X868044Y264259D02*
X864793Y247988D01*
G01X867065Y275785D02*
X869370Y264259D01*
G01X865743Y275764D02*
X868044Y264259D01*
G01X869398Y289710D02*
X867065Y275785D01*
G01X868078Y289704D02*
X865743Y275764D01*
G01X864512Y264585D02*
X861855Y279654D01*
G01X865833Y264585D02*
X863176Y279654D01*
G01X858091Y266044D02*
X854268Y244362D01*
G01X859412Y266044D02*
X855589Y244362D01*
G01X856074Y277489D02*
X858091Y266044D01*
G01X857394Y277492D02*
X859412Y266044D01*
G01D02*
X855589Y244362D01*
G01X858091Y266044D02*
X854268Y244362D01*
G01X857394Y277492D02*
X859412Y266044D01*
G01X856074Y277489D02*
X858091Y266044D01*
G01X853679Y266000D02*
X849989Y245076D01*
G01X855000Y266000D02*
X851310Y245076D01*
G01X850594Y283501D02*
X853679Y266000D01*
G01X851915Y283501D02*
X855000Y266000D01*
G01D02*
X851310Y245076D01*
G01X853679Y266000D02*
X849989Y245076D01*
G01X851915Y283501D02*
X855000Y266000D01*
G01X850594Y283501D02*
X853679Y266000D01*
G01X848575Y265959D02*
X845700Y249656D01*
G01X849896Y265959D02*
X847021Y249656D01*
G01X846187Y279501D02*
X848575Y265959D01*
G01X847508Y279501D02*
X849896Y265959D01*
G01D02*
X847021Y249656D01*
G01X848575Y265959D02*
X845700Y249656D01*
G01X847508Y279501D02*
X849896Y265959D01*
G01X846187Y279501D02*
X848575Y265959D01*
G01X843346Y266211D02*
X840649Y250915D01*
G01X844667Y266211D02*
X841970Y250915D01*
G01X841179Y278500D02*
X843346Y266211D01*
G01X842500Y278500D02*
X844667Y266211D01*
G01D02*
X841970Y250915D01*
G01X843346Y266211D02*
X840649Y250915D01*
G01X842500Y278500D02*
X844667Y266211D01*
G01X841179Y278500D02*
X843346Y266211D01*
G01X869302Y334806D02*
X877061Y287956D01*
G01X869302Y334806D02*
X877061Y287956D01*
G01X867162Y329419D02*
X874471Y287956D01*
G01X873150D02*
X865931Y328909D01*
G01X873150Y287956D02*
X865931Y328909D01*
G01X867162Y329419D02*
X874471Y287956D01*
G01X862006Y324149D02*
X868078Y289704D01*
G01X863237Y324659D02*
X869398Y289710D01*
G01X864835Y289068D02*
X858632Y324249D01*
G01X863514Y289068D02*
X857401Y323739D01*
G01X863176Y279654D02*
X864835Y289068D01*
G01X861855Y279654D02*
X863514Y289068D01*
G01X863237Y324659D02*
X869398Y289710D01*
G01X862006Y324149D02*
X868078Y289704D01*
G01X863514Y289068D02*
X857401Y323739D01*
G01X864835Y289068D02*
X858632Y324249D01*
G01X861855Y279654D02*
X863514Y289068D01*
G01X863176Y279654D02*
X864835Y289068D01*
G01X858013Y288763D02*
X856074Y277489D01*
G01X859333Y288766D02*
X857394Y277492D01*
G01X851306Y326772D02*
X858013Y288763D01*
G01X852537Y327282D02*
X859333Y288766D01*
G01D02*
X857394Y277492D01*
G01X858013Y288763D02*
X856074Y277489D01*
G01X852537Y327282D02*
X859333Y288766D01*
G01X851306Y326772D02*
X858013Y288763D01*
G01X852134Y292234D02*
X850594Y283501D01*
G01X853455Y292234D02*
X851915Y283501D01*
G01X846569Y323780D02*
X852134Y292234D01*
G01X847800Y324290D02*
X853455Y292234D01*
G01D02*
X851915Y283501D01*
G01X852134Y292234D02*
X850594Y283501D01*
G01X847800Y324290D02*
X853455Y292234D01*
G01X846569Y323780D02*
X852134Y292234D01*
G01X847740Y288311D02*
X846187Y279501D01*
G01X849061Y288311D02*
X847508Y279501D01*
G01X841755Y322240D02*
X847740Y288311D01*
G01X842986Y322750D02*
X849061Y288311D01*
G01D02*
X847508Y279501D01*
G01X847740Y288311D02*
X846187Y279501D01*
G01X842986Y322750D02*
X849061Y288311D01*
G01X841755Y322240D02*
X847740Y288311D01*
G01X843339Y290751D02*
X841179Y278500D01*
G01X844660Y290751D02*
X842500Y278500D01*
G01X841084Y311030D02*
X844660Y290751D01*
G01D02*
X842500Y278500D01*
G01X843339Y290751D02*
X841179Y278500D01*
G01X841084Y311030D02*
X844660Y290751D01*
G01X839989Y292935D02*
Y294899D01*
G01Y292935D02*
Y294899D01*
G01X878382Y287956D02*
X870537Y335309D01*
G01X878382Y287956D02*
X870537Y335309D01*
G01X845217Y816724D02*
X840417Y809869D01*
G01X845217Y816724D02*
X840417Y809869D01*
G01X846495Y848262D02*
X844282Y860811D01*
G01X845603D02*
X847816Y848262D01*
G01X845200Y840914D02*
X846495Y848262D01*
G01X847816D02*
X846500Y840800D01*
G01X845200Y824114D02*
Y840914D01*
G01X846500Y840800D02*
Y824000D01*
G01X843986Y817234D02*
X845200Y824114D01*
G01X846500Y824000D02*
X845217Y816724D01*
G01X846500Y824000D02*
X845217Y816724D01*
G01X843986Y817234D02*
X845200Y824114D01*
G01X846500Y840800D02*
Y824000D01*
G01X845200Y824114D02*
Y840914D01*
G01X847816Y848262D02*
X846500Y840800D01*
G01X845200Y840914D02*
X846495Y848262D01*
G01X845603Y860811D02*
X847816Y848262D01*
G01X846495D02*
X844282Y860811D01*
G01X845413Y867223D02*
Y872882D01*
G01X846713D02*
Y867105D01*
G01X844282Y860811D02*
X845413Y867223D01*
G01X846713Y867105D02*
X845603Y860811D01*
G01X846713Y867105D02*
X845603Y860811D01*
G01X844282D02*
X845413Y867223D01*
G01X846713Y872882D02*
Y867105D01*
G01X845413Y867223D02*
Y872882D01*
G01X903413Y64900D02*
X905063D01*
G01X898713D02*
X900363D01*
G01X903413D02*
X905063D01*
G01X898713D02*
X900363D01*
G01X907043Y59700D02*
X908693D01*
G01X902343D02*
X903993D01*
G01X897643D02*
X899293D01*
G01X907043D02*
X908693D01*
G01X902343D02*
X903993D01*
G01X897643D02*
X899293D01*
G01X879562Y71200D02*
X913626Y77209D01*
G01X879562Y69879D02*
X914136Y75978D01*
G01X879562Y69879D02*
X914136Y75978D01*
G01X879562Y71200D02*
X913626Y77209D01*
G01X880538Y74007D02*
X910258Y80336D01*
G01X880538Y74007D02*
X910258Y80336D01*
G01X902904Y84295D02*
X909104Y90495D01*
G01X903743Y83295D02*
X910374Y89926D01*
G01X901480Y83298D02*
X902904Y84295D01*
G01X901990Y82067D02*
X903743Y83295D01*
G01X879618Y79445D02*
X901480Y83298D01*
G01X879603Y78122D02*
X901990Y82067D01*
G01X903743Y83295D02*
X910374Y89926D01*
G01X902904Y84295D02*
X909104Y90495D01*
G01X901990Y82067D02*
X903743Y83295D01*
G01X901480Y83298D02*
X902904Y84295D01*
G01X879603Y78122D02*
X901990Y82067D01*
G01X879618Y79445D02*
X901480Y83298D01*
G01X903448Y89825D02*
X910305Y94630D01*
G01X902860Y91002D02*
X909372Y95564D01*
G01X903448Y89825D02*
X910305Y94630D01*
G01X896085Y88793D02*
X902860Y91002D01*
G01X896055Y87415D02*
X903448Y89825D01*
G01X892700Y90063D02*
X896085Y88793D01*
G01X892591Y88715D02*
X896055Y87415D01*
G01X889209Y89364D02*
X892700Y90063D01*
G01X889209Y88038D02*
X892591Y88715D01*
G01X880530Y75335D02*
X909752Y81558D01*
G01X903448Y89825D02*
X910305Y94630D01*
G01X902860Y91002D02*
X909372Y95564D01*
G01X896055Y87415D02*
X903448Y89825D01*
G01X896085Y88793D02*
X902860Y91002D01*
G01X892591Y88715D02*
X896055Y87415D01*
G01X892700Y90063D02*
X896085Y88793D01*
G01X889209Y88038D02*
X892591Y88715D01*
G01X889209Y89364D02*
X892700Y90063D01*
G01X880530Y75335D02*
X909752Y81558D01*
G01X889544Y93698D02*
X875825Y96442D01*
G01X889544Y92372D02*
X875585Y95164D01*
G01X894098Y94609D02*
X889544Y93698D01*
G01X893986Y93260D02*
X889544Y92372D01*
G01X896263Y93787D02*
X894098Y94609D01*
G01X896220Y92413D02*
X893986Y93260D01*
G01X898431Y94457D02*
X896263Y93787D01*
G01X899010Y93275D02*
X896220Y92413D01*
G01X911734Y103773D02*
X898431Y94457D01*
G01X912573Y102773D02*
X899010Y93275D01*
G01X894100Y107300D02*
X907298Y109627D01*
G01X894100Y105979D02*
X907792Y108394D01*
G01X893875Y106018D02*
X894100Y105979D01*
G01X888813Y108232D02*
X894100Y107300D01*
G01X893875Y106018D02*
X894100Y105979D01*
G01X888813Y106911D02*
X893875Y106019D01*
G01X893348Y103256D02*
X907646Y105778D01*
G01X893348Y101935D02*
X908145Y104545D01*
G01X888140Y104174D02*
X893348Y103256D01*
G01X888140Y102853D02*
X893348Y101935D01*
G01X889544Y92372D02*
X875585Y95164D01*
G01X889544Y93698D02*
X875825Y96442D01*
G01X893986Y93260D02*
X889544Y92372D01*
G01X894098Y94609D02*
X889544Y93698D01*
G01X896220Y92413D02*
X893986Y93260D01*
G01X896263Y93787D02*
X894098Y94609D01*
G01X899010Y93275D02*
X896220Y92413D01*
G01X898431Y94457D02*
X896263Y93787D01*
G01X912573Y102773D02*
X899010Y93275D01*
G01X911734Y103773D02*
X898431Y94457D01*
G01X894100Y105979D02*
X907792Y108394D01*
G01X894100Y107300D02*
X907298Y109627D01*
G01X893875Y106018D02*
X894100Y105979D01*
G01Y107300D02*
X907298Y109627D01*
G01X888813Y108232D02*
X894100Y107300D01*
G01X888813Y106911D02*
X893875Y106019D01*
G01X888813Y108232D02*
X894100Y107300D01*
G01X893348Y101935D02*
X908145Y104545D01*
G01X893348Y103256D02*
X907646Y105778D01*
G01X888140Y102853D02*
X893348Y101935D01*
G01X888140Y104174D02*
X893348Y103256D01*
G01X907298Y109627D02*
X912277Y112943D01*
G01X905689Y112738D02*
X906571Y113197D01*
G01X906112Y111492D02*
X907172Y112044D01*
G01X894698Y110801D02*
X905689Y112738D01*
G01X894698Y109480D02*
X906112Y111492D01*
G01X888033Y111976D02*
X894698Y110801D01*
G01X888033Y110655D02*
X894698Y109480D01*
G01X874766Y109637D02*
X888033Y111976D01*
G01X874762Y108316D02*
X888033Y110655D01*
G01X907298Y109627D02*
X912277Y112943D01*
G01X906112Y111492D02*
X907172Y112044D01*
G01X905689Y112738D02*
X906571Y113197D01*
G01X894698Y109480D02*
X906112Y111492D01*
G01X894698Y110801D02*
X905689Y112738D01*
G01X888033Y110655D02*
X894698Y109480D01*
G01X888033Y111976D02*
X894698Y110801D01*
G01X874762Y108316D02*
X888033Y110655D01*
G01X874766Y109637D02*
X888033Y111976D01*
G01X892699Y187499D02*
G02X890770Y186700I-1929J1929D01*
G01X891781Y188420D02*
G02X890769Y188000I-1013J1013D01*
G01X893263Y188272D02*
G02X892701Y187500I-2735J1400D01*
G01X892105Y188865D02*
G02X891781Y188420I-1577J808D01*
G01X892286Y189459D02*
G02X892105Y188865I-1759J211D01*
G01X893578Y189303D02*
G02X893263Y188272I-3051J368D01*
G01X892105Y188865D02*
G02X891781Y188420I-1577J808D01*
G01X892286Y189459D02*
G02X892105Y188865I-1759J211D01*
G01X892300Y189673D02*
G02X892287Y189460I-1772J1D01*
G01X891781Y188420D02*
G02X890769Y188000I-1013J1013D01*
G01X892699Y187499D02*
G02X890770Y186700I-1929J1929D01*
G01X892105Y188865D02*
G02X891781Y188420I-1577J808D01*
G01X893263Y188272D02*
G02X892701Y187500I-2735J1400D01*
G01X893578Y189303D02*
G02X893263Y188272I-3051J368D01*
G01X892286Y189459D02*
G02X892105Y188865I-1759J211D01*
G01X893263Y188272D02*
G02X892701Y187500I-2735J1400D01*
G01X893578Y189303D02*
G02X893263Y188272I-3051J368D01*
G01X892300Y189673D02*
G02X892287Y189460I-1772J1D01*
G01X893578Y189303D02*
G02X893263Y188272I-3051J368D01*
G01X903300Y272695D02*
Y264400D01*
G01X904600Y272581D02*
Y264400D01*
G01X907631Y297264D02*
X903300Y272695D01*
G01X908952Y297264D02*
X904600Y272581D01*
G01D02*
Y264400D01*
G01X903300Y272695D02*
Y264400D01*
G01X908952Y297264D02*
X904600Y272581D01*
G01X907631Y297264D02*
X903300Y272695D01*
G01X899400D02*
Y264400D01*
G01X900700Y272581D02*
Y264400D01*
G01X903760Y297427D02*
X899400Y272695D01*
G01X905081Y297427D02*
X900700Y272581D01*
G01D02*
Y264400D01*
G01X899400Y272695D02*
Y264400D01*
G01X905081Y297427D02*
X900700Y272581D01*
G01X903760Y297427D02*
X899400Y272695D01*
G01X891450D02*
Y264250D01*
G01X892750D02*
Y272581D01*
G01X895652Y296534D02*
X891450Y272695D01*
G01X892750Y272581D02*
X896973Y296534D01*
G01X895475Y272695D02*
Y264300D01*
G01X896775Y272581D02*
Y264300D01*
G01X899717Y296758D02*
X895475Y272695D01*
G01X901038Y296758D02*
X896775Y272581D01*
G01X892750D02*
X896973Y296534D01*
G01X895652D02*
X891450Y272695D01*
G01X892750Y264250D02*
Y272581D01*
G01X891450Y272695D02*
Y264250D01*
G01X896775Y272581D02*
Y264300D01*
G01X895475Y272695D02*
Y264300D01*
G01X901038Y296758D02*
X896775Y272581D01*
G01X899717Y296758D02*
X895475Y272695D01*
G01X883550D02*
Y264300D01*
G01X884850Y272583D02*
Y264594D01*
G01X886805Y291601D02*
X883550Y272695D01*
G01X888125Y291604D02*
X884851Y272583D01*
G01X887550Y273593D02*
Y265162D01*
G01X888850Y273479D02*
Y264868D01*
G01X891238Y294512D02*
X887550Y273593D01*
G01X892559Y294512D02*
X888850Y273479D01*
G01X884850Y272583D02*
Y264594D01*
G01X883550Y272695D02*
Y264300D01*
G01X888125Y291604D02*
X884851Y272583D01*
G01X886805Y291601D02*
X883550Y272695D01*
G01X888850Y273479D02*
Y264868D01*
G01X887550Y273593D02*
Y265162D01*
G01X892559Y294512D02*
X888850Y273479D01*
G01X891238Y294512D02*
X887550Y273593D01*
G01X875550Y279380D02*
Y262894D01*
G01X876850Y263188D02*
Y279266D01*
G01X879627Y272269D02*
X879700Y262900D01*
G01X880928Y272193D02*
X880998Y263197D01*
G01X882160Y292581D02*
X879627Y272269D01*
G01X883475Y292614D02*
X880928Y272193D01*
G01X876850Y263188D02*
Y279266D01*
G01X875550Y279380D02*
Y262894D01*
G01X880928Y272193D02*
X880998Y263197D01*
G01X879627Y272269D02*
X879700Y262900D01*
G01X883475Y292614D02*
X880928Y272193D01*
G01X882160Y292581D02*
X879627Y272269D01*
G01X906179Y305500D02*
X907631Y297264D01*
G01X913441Y346673D02*
X906179Y305500D01*
G01D02*
X907631Y297264D01*
G01X913441Y346673D02*
X906179Y305500D01*
G01X901215Y311860D02*
X903760Y297427D01*
G01X902536Y311860D02*
X905081Y297427D01*
G01X902536Y311860D02*
X905081Y297427D01*
G01X901215Y311860D02*
X903760Y297427D01*
G01X892704Y313250D02*
X895652Y296534D01*
G01X896973D02*
X893996Y313410D01*
G01X897081Y311701D02*
X899717Y296758D01*
G01X898402Y311701D02*
X901038Y296758D01*
G01X896973Y296534D02*
X893996Y313410D01*
G01X892704Y313250D02*
X895652Y296534D01*
G01X898402Y311701D02*
X901038Y296758D01*
G01X897081Y311701D02*
X899717Y296758D01*
G01X878333Y339624D02*
X886805Y291601D01*
G01X879564Y340134D02*
X888125Y291604D01*
G01X882226Y345628D02*
X891238Y294512D01*
G01X883457Y346138D02*
X892559Y294512D01*
G01X879564Y340134D02*
X888125Y291604D01*
G01X878333Y339624D02*
X886805Y291601D01*
G01X883457Y346138D02*
X892559Y294512D01*
G01X882226Y345628D02*
X891238Y294512D01*
G01X877061Y287956D02*
X875550Y279380D01*
G01X876850Y279266D02*
X878382Y287956D01*
G01X874776Y334485D02*
X882160Y292581D01*
G01X876007Y334995D02*
X883475Y292614D01*
G01X876850Y279266D02*
X878382Y287956D01*
G01X877061D02*
X875550Y279380D01*
G01X876007Y334995D02*
X883475Y292614D01*
G01X874776Y334485D02*
X882160Y292581D01*
G01X903148Y322825D02*
X901215Y311860D01*
G01X904469Y322825D02*
X902536Y311860D01*
G01X897922Y352465D02*
X903148Y322825D01*
G01X899153Y352975D02*
X904469Y322826D01*
G01Y322825D02*
X902536Y311860D01*
G01X903148Y322825D02*
X901215Y311860D01*
G01X899153Y352975D02*
X904469Y322826D01*
G01X897922Y352465D02*
X903148Y322825D01*
G01X890529Y343190D02*
X892704Y313250D01*
G01X893996Y313410D02*
X891800Y343642D01*
G01X898670Y320710D02*
X897081Y311701D01*
G01X899991Y320710D02*
X898402Y311701D01*
G01X893640Y349235D02*
X898670Y320710D01*
G01X894871Y349745D02*
X899991Y320710D01*
G01X893996Y313410D02*
X891800Y343642D01*
G01X890529Y343190D02*
X892704Y313250D01*
G01X899991Y320710D02*
X898402Y311701D01*
G01X898670Y320710D02*
X897081Y311701D01*
G01X894871Y349745D02*
X899991Y320710D01*
G01X893640Y349235D02*
X898670Y320710D01*
G01X916476Y64433D02*
X930991Y78950D01*
G01X915556Y65353D02*
X930072Y79870D01*
G01X914464Y63600D02*
G03X916476Y64433I0J2847D01*
G01X914463Y64900D02*
G03X915556Y65353I0J1546D01*
G01X912813Y64900D02*
X914463D01*
G01X908113D02*
X909763D01*
G01X915556Y65353D02*
X930072Y79870D01*
G01X916476Y64433D02*
X930991Y78950D01*
G01X914463Y64900D02*
G03X915556Y65353I0J1546D01*
G01X914464Y63600D02*
G03X916476Y64433I0J2847D01*
G01X912813Y64900D02*
X914463D01*
G01X908113D02*
X909763D01*
G01X918015Y60314D02*
X939507Y81807D01*
G01X917095Y61234D02*
X938587Y82727D01*
G01X913392Y58400D02*
G03X918015Y60314I1J6537D01*
G01X913393Y59700D02*
G03X917095Y61234I-1J5236D01*
G01X911743Y59700D02*
X913393D01*
G01X917095Y61234D02*
X938587Y82727D01*
G01X918015Y60314D02*
X939507Y81807D01*
G01X913393Y59700D02*
G03X917095Y61234I-1J5236D01*
G01X913392Y58400D02*
G03X918015Y60314I1J6537D01*
G01X911743Y59700D02*
X913393D01*
G01X940100Y101140D02*
Y113800D01*
G01X938800Y101140D02*
Y113800D01*
G01X939365Y99365D02*
G03X940100Y101140I-1776J1775D01*
G01X938445Y100285D02*
G03X938800Y101140I-855J856D01*
G01X938900Y98243D02*
G02X939365Y99365I1586J0D01*
G01X937600Y98243D02*
G02X938445Y100285I2887J1D01*
G01X938900Y97179D02*
Y98243D01*
G01X937600Y97179D02*
Y98243D01*
G01X937642Y94142D02*
G03X938900Y97179I-3037J3037D01*
G01X936722Y95062D02*
G03X937600Y97179I-2116J2118D01*
G01X933621Y90121D02*
X937642Y94142D01*
G01X932701Y91041D02*
X936722Y95062D01*
G01X932500Y87414D02*
G02X933621Y90121I3829J0D01*
G01X931200Y87414D02*
G02X932701Y91041I5129J1D01*
G01X932500Y82591D02*
Y87414D01*
G01X931200Y82591D02*
Y87414D01*
G01X930992Y78950D02*
G03X932500Y82591I-3642J3641D01*
G01X930072Y79870D02*
G03X931200Y82591I-2721J2722D01*
G01X938800Y101140D02*
Y113800D01*
G01X940100Y101140D02*
Y113800D01*
G01X938445Y100285D02*
G03X938800Y101140I-855J856D01*
G01X939365Y99365D02*
G03X940100Y101140I-1776J1775D01*
G01X937600Y98243D02*
G02X938445Y100285I2887J1D01*
G01X938900Y98243D02*
G02X939365Y99365I1586J0D01*
G01X937600Y97179D02*
Y98243D01*
G01X938900Y97179D02*
Y98243D01*
G01X936722Y95062D02*
G03X937600Y97179I-2116J2118D01*
G01X937642Y94142D02*
G03X938900Y97179I-3037J3037D01*
G01X932701Y91041D02*
X936722Y95062D01*
G01X933621Y90121D02*
X937642Y94142D01*
G01X931200Y87414D02*
G02X932701Y91041I5129J1D01*
G01X932500Y87414D02*
G02X933621Y90121I3829J0D01*
G01X931200Y82591D02*
Y87414D01*
G01X932500Y82591D02*
Y87414D01*
G01X930072Y79870D02*
G03X931200Y82591I-2721J2722D01*
G01X930992Y78950D02*
G03X932500Y82591I-3642J3641D01*
G01X940848Y93742D02*
X941755Y94649D01*
G01X940900Y90727D02*
G02X941768Y92822I2962J0D01*
G01X939600Y90727D02*
G02X940848Y93742I4263J1D01*
G01X940900Y85170D02*
Y90727D01*
G01X939600Y85170D02*
Y90727D01*
G01X939507Y81807D02*
G03X940900Y85170I-3363J3363D01*
G01X938587Y82727D02*
G03X939600Y85170I-2442J2444D01*
G01X940848Y93742D02*
X941755Y94649D01*
G01X939600Y90727D02*
G02X940848Y93742I4263J1D01*
G01X940900Y90727D02*
G02X941768Y92822I2962J0D01*
G01X939600Y85170D02*
Y90727D01*
G01X940900Y85170D02*
Y90727D01*
G01X938587Y82727D02*
G03X939600Y85170I-2442J2444D01*
G01X939507Y81807D02*
G03X940900Y85170I-3363J3363D01*
G01X935955Y103046D02*
Y111337D01*
G01X937255Y102507D02*
Y111337D01*
G01X931629Y98720D02*
X935955Y103046D01*
G01X932629Y97881D02*
X937255Y102507D01*
G01X919388Y81244D02*
X931629Y98720D01*
G01X920322Y80310D02*
X932629Y97881D01*
G01X916508Y79228D02*
X919388Y81244D01*
G01X914136Y75978D02*
X920322Y80310D01*
G01X913626Y77209D02*
X916508Y79227D01*
G01X914136Y75978D02*
X920322Y80310D01*
G01X918223Y97012D02*
X927330Y110013D01*
G01X919157Y96078D02*
X928395Y109267D01*
G01X909281Y90748D02*
X918223Y97012D01*
G01X910374Y89926D02*
X919157Y96078D01*
G01X937255Y102507D02*
Y111337D01*
G01X935955Y103046D02*
Y111337D01*
G01X932629Y97881D02*
X937255Y102507D01*
G01X931629Y98720D02*
X935955Y103046D01*
G01X920322Y80310D02*
X932629Y97881D01*
G01X919388Y81244D02*
X931629Y98720D01*
G01X914136Y75978D02*
X920322Y80310D01*
G01X916508Y79228D02*
X919388Y81244D01*
G01X913626Y77209D02*
X916508Y79227D01*
G01X919157Y96078D02*
X928395Y109267D01*
G01X918223Y97012D02*
X927330Y110013D01*
G01X910374Y89926D02*
X919157Y96078D01*
G01X909281Y90748D02*
X918223Y97012D01*
G01X915755Y102735D02*
X923085Y110065D01*
G01X916757Y101898D02*
X924005Y109146D01*
G01X914624Y101104D02*
X915755Y102735D01*
G01X915552Y100160D02*
X916757Y101898D01*
G01X914594Y101084D02*
X914624Y101104D01*
G01X912874Y98292D02*
X915340Y100018D01*
G01X911938Y99225D02*
X914594Y101084D01*
G01X915348Y100023D02*
X915552Y100160D01*
G01X912874Y98292D02*
X915340Y100018D01*
G01X909371Y95564D02*
X911939Y99224D01*
G01X910309Y94636D02*
X912874Y98292D01*
G01X909372Y95564D02*
X909371D01*
G01X933130Y106510D02*
Y112005D01*
G01X934430Y106124D02*
Y112005D01*
G01X931752Y104388D02*
X933130Y106510D01*
G01X932692Y103448D02*
X934430Y106124D01*
G01X923641Y99118D02*
X931752Y104388D01*
G01X924581Y98178D02*
X932692Y103448D01*
G01X916248Y87734D02*
X923641Y99118D01*
G01X917470Y87227D02*
X924581Y98178D01*
G01X915877Y85994D02*
X916248Y87734D01*
G01X917099Y85487D02*
X917470Y87227D01*
G01X915363Y85201D02*
X915877Y85994D01*
G01X916303Y84261D02*
X917099Y85487D01*
G01X909752Y81558D02*
X915363Y85201D01*
G01X910258Y80336D02*
X916303Y84261D01*
G01X916757Y101898D02*
X924005Y109146D01*
G01X915755Y102735D02*
X923085Y110065D01*
G01X915552Y100160D02*
X916757Y101898D01*
G01X914624Y101104D02*
X915755Y102735D01*
G01X915348Y100023D02*
X915552Y100160D01*
G01X911938Y99225D02*
X914594Y101084D01*
G01X912874Y98292D02*
X915340Y100018D01*
G01X914594Y101084D02*
X914624Y101104D01*
G01X911938Y99225D02*
X914594Y101084D01*
G01X910309Y94636D02*
X912874Y98292D01*
G01X909371Y95564D02*
X911939Y99224D01*
G01X909372Y95564D02*
X909371D01*
G01X934430Y106124D02*
Y112005D01*
G01X933130Y106510D02*
Y112005D01*
G01X932692Y103448D02*
X934430Y106124D01*
G01X931752Y104388D02*
X933130Y106510D01*
G01X924581Y98178D02*
X932692Y103448D01*
G01X923641Y99118D02*
X931752Y104388D01*
G01X917470Y87227D02*
X924581Y98178D01*
G01X916248Y87734D02*
X923641Y99118D01*
G01X917099Y85487D02*
X917470Y87227D01*
G01X915877Y85994D02*
X916248Y87734D01*
G01X916303Y84261D02*
X917099Y85487D01*
G01X915363Y85201D02*
X915877Y85994D01*
G01X910258Y80336D02*
X916303Y84261D01*
G01X909752Y81558D02*
X915363Y85201D01*
G01X919846Y111885D02*
X911734Y103773D01*
G01X920766Y110966D02*
X912573Y102773D01*
G01X907646Y105778D02*
X914337Y110307D01*
G01X908145Y104545D02*
X915204Y109324D01*
G01X920766Y110966D02*
X912573Y102773D01*
G01X919846Y111885D02*
X911734Y103773D01*
G01X908145Y104545D02*
X915204Y109324D01*
G01X907646Y105778D02*
X914337Y110307D01*
G01X927330Y110042D02*
X929534Y112246D01*
G01X928395Y109267D02*
X930454Y111326D01*
G01X928395Y109267D02*
X930454Y111326D01*
G01X927330Y110042D02*
X929534Y112246D01*
G01X912277Y112943D02*
X912750Y113247D01*
G01X907792Y108394D02*
X913453Y112153D01*
G01X907792Y108394D02*
X913453Y112153D01*
G01X914337Y110307D02*
X914659Y110674D01*
G01X915204Y109324D02*
X915636Y109816D01*
G01X907792Y108394D02*
X913453Y112153D01*
G01X912277Y112943D02*
X912750Y113247D01*
G01X915204Y109324D02*
X915636Y109816D01*
G01X914337Y110307D02*
X914659Y110674D01*
G01X934700Y274429D02*
X938679Y297000D01*
G01X936000Y274315D02*
X940000Y297000D01*
G01X934700Y265000D02*
Y274429D01*
G01X936000Y265000D02*
Y274315D01*
G01X938700Y272695D02*
X943139Y297882D01*
G01X940000Y272581D02*
X944460Y297882D01*
G01X938700Y265100D02*
Y272695D01*
G01X940000Y265100D02*
Y272581D01*
G01X936000Y274315D02*
X940000Y297000D01*
G01X934700Y274429D02*
X938679Y297000D01*
G01X936000Y265000D02*
Y274315D01*
G01X934700Y265000D02*
Y274429D01*
G01X940000Y272581D02*
X944460Y297882D01*
G01X938700Y272695D02*
X943139Y297882D01*
G01X940000Y265100D02*
Y272581D01*
G01X938700Y265100D02*
Y272695D01*
G01X930800D02*
X934947Y296217D01*
G01X932100Y272581D02*
X936268Y296217D01*
G01X930800Y265194D02*
Y272695D01*
G01X932100Y264900D02*
Y272581D01*
G01X928200D02*
X932575Y297397D01*
G01X926900Y272695D02*
X931254Y297397D01*
G01X928200Y264826D02*
Y272581D01*
G01X926900Y265120D02*
Y272695D01*
G01X932100Y272581D02*
X936268Y296217D01*
G01X930800Y272695D02*
X934947Y296217D01*
G01X932100Y264900D02*
Y272581D01*
G01X930800Y265194D02*
Y272695D01*
G01X926900D02*
X931254Y297397D01*
G01X928200Y272581D02*
X932575Y297397D01*
G01X926900Y265120D02*
Y272695D01*
G01X928200Y264826D02*
Y272581D01*
G01X923000Y272467D02*
Y264994D01*
G01X924300Y272581D02*
Y264700D01*
G01X921998Y278144D02*
X923000Y272467D01*
G01X923319Y278144D02*
X924300Y272581D01*
G01X920200D02*
Y264700D01*
G01X918900Y272467D02*
Y264700D01*
G01X919374Y277272D02*
X920200Y272581D01*
G01X918053Y277272D02*
X918900Y272467D01*
G01X924300Y272581D02*
Y264700D01*
G01X923000Y272467D02*
Y264994D01*
G01X923319Y278144D02*
X924300Y272581D01*
G01X921998Y278144D02*
X923000Y272467D01*
G01X918900D02*
Y264700D01*
G01X920200Y272581D02*
Y264700D01*
G01X918053Y277272D02*
X918900Y272467D01*
G01X919374Y277272D02*
X920200Y272581D01*
G01X916400D02*
Y264700D01*
G01X915100Y272467D02*
Y264994D01*
G01X915688Y276621D02*
X916400Y272581D01*
G01X914367Y276621D02*
X915100Y272467D01*
G01X918790Y294213D02*
X915688Y276621D01*
G01X917469Y294213D02*
X914367Y276621D01*
G01X915100Y272467D02*
Y264994D01*
G01X916400Y272581D02*
Y264700D01*
G01X914367Y276621D02*
X915100Y272467D01*
G01X915688Y276621D02*
X916400Y272581D01*
G01X917469Y294213D02*
X914367Y276621D01*
G01X918790Y294213D02*
X915688Y276621D01*
G01X911100Y272467D02*
Y265194D01*
G01X912400Y272581D02*
Y264900D01*
G01X910593Y275338D02*
X911100Y272467D01*
G01X911914Y275338D02*
X912400Y272581D01*
G01X913693Y292920D02*
X910593Y275338D01*
G01X915014Y292920D02*
X911914Y275338D01*
G01X912400Y272581D02*
Y264900D01*
G01X911100Y272467D02*
Y265194D01*
G01X911914Y275338D02*
X912400Y272581D01*
G01X910593Y275338D02*
X911100Y272467D01*
G01X915014Y292920D02*
X911914Y275338D01*
G01X913693Y292920D02*
X910593Y275338D01*
G01X938679Y297000D02*
X936018Y312089D01*
G01X940000Y297000D02*
X937339Y312089D01*
G01X943139Y297882D02*
X940269Y314161D01*
G01X940000Y297000D02*
X937339Y312089D01*
G01X938679Y297000D02*
X936018Y312089D01*
G01X943139Y297882D02*
X940269Y314161D01*
G01X934947Y296217D02*
X932220Y311684D01*
G01X936268Y296217D02*
X933541Y311684D01*
G01X932575Y297397D02*
X930000Y312000D01*
G01X931254Y297397D02*
X928679Y312000D01*
G01X936268Y296217D02*
X933541Y311684D01*
G01X934947Y296217D02*
X932220Y311684D01*
G01X931254Y297397D02*
X928679Y312000D01*
G01X932575Y297397D02*
X930000Y312000D01*
G01X925349Y297146D02*
X921998Y278144D01*
G01X926670Y297146D02*
X923319Y278144D01*
G01X923633Y306880D02*
X925349Y297146D01*
G01X924954Y306880D02*
X926670Y297146D01*
G01X930367Y345072D02*
X923633Y306880D01*
G01X931688Y345072D02*
X924954Y306880D01*
G01X922500Y295000D02*
X919374Y277272D01*
G01X921179Y295000D02*
X918053Y277272D01*
G01X920629Y305611D02*
X922500Y295000D01*
G01X919308Y305611D02*
X921179Y295000D01*
G01X927391Y343960D02*
X920629Y305611D01*
G01X926070Y343960D02*
X919308Y305611D01*
G01X926670Y297146D02*
X923319Y278144D01*
G01X925349Y297146D02*
X921998Y278144D01*
G01X924954Y306880D02*
X926670Y297146D01*
G01X923633Y306880D02*
X925349Y297146D01*
G01X931688Y345072D02*
X924954Y306880D01*
G01X930367Y345072D02*
X923633Y306880D01*
G01X921179Y295000D02*
X918053Y277272D01*
G01X922500Y295000D02*
X919374Y277272D01*
G01X919308Y305611D02*
X921179Y295000D01*
G01X920629Y305611D02*
X922500Y295000D01*
G01X926070Y343960D02*
X919308Y305611D01*
G01X927391Y343960D02*
X920629Y305611D01*
G01X916746Y305808D02*
X918790Y294213D01*
G01X915425Y305808D02*
X917469Y294213D01*
G01X923387Y343471D02*
X916746Y305808D01*
G01X922066Y343471D02*
X915425Y305808D01*
G01D02*
X917469Y294213D01*
G01X916746Y305808D02*
X918790Y294213D01*
G01X922066Y343471D02*
X915425Y305808D01*
G01X923387Y343471D02*
X916746Y305808D01*
G01X911343Y306250D02*
X913693Y292920D01*
G01X912664Y306250D02*
X915014Y292920D01*
G01X917926Y343591D02*
X911343Y306250D01*
G01X919247Y343591D02*
X912664Y306250D01*
G01D02*
X915014Y292920D01*
G01X911343Y306250D02*
X913693Y292920D01*
G01X919247Y343591D02*
X912664Y306250D01*
G01X917926Y343591D02*
X911343Y306250D01*
G01X907500Y305500D02*
X908952Y297264D01*
G01X914762Y346673D02*
X907500Y305500D01*
G01D02*
X908952Y297264D01*
G01X914762Y346673D02*
X907500Y305500D01*
G01X936018Y312089D02*
X942561Y349197D01*
G01X937339Y312089D02*
X943882Y349195D01*
G01X940269Y314161D02*
X946632Y350250D01*
G01X937339Y312089D02*
X943882Y349195D01*
G01X936018Y312089D02*
X942561Y349197D01*
G01X940269Y314161D02*
X946632Y350250D01*
G01X932220Y311684D02*
X938540Y347525D01*
G01X933541Y311684D02*
X939861Y347523D01*
G01X930000Y312000D02*
X936126Y346740D01*
G01X928679Y312000D02*
X934805Y346742D01*
G01X933541Y311684D02*
X939861Y347523D01*
G01X932220Y311684D02*
X938540Y347525D01*
G01X928679Y312000D02*
X934805Y346742D01*
G01X930000Y312000D02*
X936126Y346740D01*
G01X911758Y432616D02*
X927391Y343960D01*
G01X910527Y432106D02*
X926070Y343960D01*
G01X910527Y432106D02*
X926070Y343960D01*
G01X911758Y432616D02*
X927391Y343960D01*
G01X915192Y389945D02*
X923387Y343471D01*
G01X913961Y389435D02*
X922066Y343471D01*
G01X913961Y389435D02*
X922066Y343471D01*
G01X915192Y389945D02*
X923387Y343471D01*
G01X910484Y385798D02*
X917926Y343591D01*
G01X911715Y386308D02*
X919247Y343591D01*
G01X911715Y386308D02*
X919247Y343591D01*
G01X910484Y385798D02*
X917926Y343591D01*
G01X942561Y349197D02*
X925461Y446171D01*
G01X943882Y349195D02*
X926692Y446681D01*
G01X943882Y349195D02*
X926692Y446681D01*
G01X942561Y349197D02*
X925461Y446171D01*
G01X938540Y347525D02*
X922070Y440931D01*
G01X939861Y347523D02*
X923301Y441441D01*
G01X936126Y346740D02*
X919397Y441619D01*
G01X934805Y346742D02*
X918166Y441109D01*
G01X939861Y347523D02*
X923301Y441441D01*
G01X938540Y347525D02*
X922070Y440931D01*
G01X934805Y346742D02*
X918166Y441109D01*
G01X936126Y346740D02*
X919397Y441619D01*
G01X913596Y440182D02*
X930367Y345072D01*
G01X914827Y440692D02*
X931688Y345072D01*
G01X914827Y440692D02*
X931688Y345072D01*
G01X913596Y440182D02*
X930367Y345072D01*
G01X907574Y379942D02*
X913441Y346673D01*
G01X908805Y380452D02*
X914762Y346673D01*
G01X908805Y380452D02*
X914762Y346673D01*
G01X907574Y379942D02*
X913441Y346673D01*
G01X951179Y351500D02*
X933353Y452599D01*
G01X951179Y351500D02*
X933353Y452599D01*
G01X946632Y350250D02*
X928857Y451078D01*
G01X947953Y350250D02*
X930088Y451588D01*
G01X947953Y350250D02*
X930088Y451588D01*
G01X946632Y350250D02*
X928857Y451078D01*
G01X937001Y454735D02*
X954899Y353224D01*
G01X938232Y455245D02*
X956220Y353224D01*
G01X938232Y455245D02*
X956220Y353224D01*
G01X937001Y454735D02*
X954899Y353224D01*
G01X952500Y351500D02*
X934584Y453109D01*
G01X952500Y351500D02*
X934584Y453109D01*
G01X958994Y349788D02*
X939528Y460187D01*
G01X960315Y349786D02*
X940759Y460697D01*
G01X960315Y349786D02*
X940759Y460697D01*
G01X958994Y349788D02*
X939528Y460187D01*
G01X988832Y59433D02*
X953250Y95015D01*
G01X988202Y58223D02*
X951950Y94476D01*
G01X988202Y58223D02*
X951950Y94476D01*
G01X988832Y59433D02*
X953250Y95015D01*
G01X967599Y71217D02*
X953112Y81490D01*
G01X967599Y71217D02*
X953112Y81490D01*
G01X967599Y71217D02*
X953112Y81490D01*
G01X967599Y71217D02*
X953112Y81490D01*
G01X971716Y69892D02*
X961622Y77050D01*
G01X967599Y71217D02*
X953112Y81490D01*
G01X975172Y67441D02*
X971716Y69892D01*
G01X974330Y66444D02*
X967599Y71217D01*
G01X986512Y54262D02*
X974330Y66444D01*
G01X967599Y71217D02*
X953112Y81490D01*
G01X971716Y69892D02*
X961622Y77050D01*
G01X974330Y66444D02*
X967599Y71217D01*
G01X975172Y67441D02*
X971716Y69892D01*
G01X986512Y54262D02*
X974330Y66444D01*
G01X974836Y106726D02*
X999349Y82214D01*
G01X998723Y81000D02*
X973536Y106187D01*
G01D02*
Y114345D01*
G01X967400Y105800D02*
Y118400D01*
G01X968700Y106339D02*
Y119603D01*
G01X997600Y75600D02*
X967400Y105800D01*
G01X998226Y76814D02*
X968700Y106339D01*
G01X964200Y102369D02*
Y113000D01*
G01X965500Y102908D02*
Y114838D01*
G01X996069Y70500D02*
X964200Y102369D01*
G01X996695Y71714D02*
X965500Y102908D01*
G01X962550Y99281D02*
Y111484D01*
G01X961250Y98742D02*
Y111484D01*
G01X995318Y66514D02*
X962550Y99281D01*
G01X994692Y65300D02*
X961250Y98742D01*
G01X958275Y106614D02*
Y109159D01*
G01X959575Y106075D02*
Y109698D01*
G01X956600Y104939D02*
X958275Y106614D01*
G01X957900Y104400D02*
X959575Y106075D01*
G01X956600Y96403D02*
Y104939D01*
G01X957900Y96942D02*
Y104400D01*
G01X991403Y61600D02*
X956600Y96403D01*
G01X992029Y62814D02*
X957900Y96942D01*
G01X973536Y106187D02*
Y114345D01*
G01X998723Y81000D02*
X973536Y106187D01*
G01X974836Y106726D02*
X999349Y82214D01*
G01X968700Y106339D02*
Y119603D01*
G01X967400Y105800D02*
Y118400D01*
G01X998226Y76814D02*
X968700Y106339D01*
G01X997600Y75600D02*
X967400Y105800D01*
G01X965500Y102908D02*
Y114838D01*
G01X964200Y102369D02*
Y113000D01*
G01X996695Y71714D02*
X965500Y102908D01*
G01X996069Y70500D02*
X964200Y102369D01*
G01X961250Y98742D02*
Y111484D01*
G01X962550Y99281D02*
Y111484D01*
G01X994692Y65300D02*
X961250Y98742D01*
G01X995318Y66514D02*
X962550Y99281D01*
G01X959575Y106075D02*
Y109698D01*
G01X958275Y106614D02*
Y109159D01*
G01X957900Y104400D02*
X959575Y106075D01*
G01X956600Y104939D02*
X958275Y106614D01*
G01X957900Y96942D02*
Y104400D01*
G01X956600Y96403D02*
Y104939D01*
G01X992029Y62814D02*
X957900Y96942D01*
G01X991403Y61600D02*
X956600Y96403D01*
G01X953250Y95015D02*
Y112168D01*
G01X951950Y94476D02*
Y111629D01*
G01Y94476D02*
Y111629D01*
G01X953250Y95015D02*
Y112168D01*
G01X947587Y95027D02*
Y142267D01*
G01X946287Y94658D02*
Y142267D01*
G01X951425Y88802D02*
X947587Y95027D01*
G01X950125Y88433D02*
X946287Y94658D01*
G01X951425Y85017D02*
Y88802D01*
G01X950125Y84478D02*
Y88433D01*
G01X953954Y82488D02*
X951425Y85017D01*
G01X953112Y81490D02*
X950125Y84478D01*
G01X955300Y81534D02*
X953954Y82488D01*
G01X956276Y81700D02*
X955300Y81534D01*
G01X959134Y78815D02*
X957788Y79769D01*
G01X960110Y78981D02*
X959134Y78815D01*
G01X946287Y94658D02*
Y142267D01*
G01X947587Y95027D02*
Y142267D01*
G01X950125Y88433D02*
X946287Y94658D01*
G01X951425Y88802D02*
X947587Y95027D01*
G01X950125Y84478D02*
Y88433D01*
G01X951425Y85017D02*
Y88802D01*
G01X953112Y81490D02*
X950125Y84478D01*
G01X953954Y82488D02*
X951425Y85017D01*
G01X955300Y81534D02*
X953954Y82488D01*
G01X956276Y81700D02*
X955300Y81534D01*
G01X959134Y78815D02*
X957788Y79769D01*
G01X960110Y78981D02*
X959134Y78815D01*
G01X944800Y102667D02*
Y142932D01*
G01X943500Y102667D02*
Y142966D01*
G01X944258Y101358D02*
G03X944800Y102667I-1310J1309D01*
G01X943338Y102278D02*
G03X943500Y102667I-389J390D01*
G01X943899Y100999D02*
X944258Y101358D01*
G01X942980Y101919D02*
X943338Y102278D01*
G01X943737Y100609D02*
G02X943899Y100999I552J-1D01*
G01X942437Y100610D02*
G02X942980Y101919I1852J-1D01*
G01X943737Y96293D02*
Y100609D01*
G01X942437Y96293D02*
Y100610D01*
G01X942675Y93729D02*
G03X943737Y96293I-2564J2564D01*
G01X941755Y94649D02*
G03X942437Y96293I-1644J1645D01*
G01X941768Y92822D02*
X942675Y93729D01*
G01X943500Y102667D02*
Y142966D01*
G01X944800Y102667D02*
Y142932D01*
G01X943338Y102278D02*
G03X943500Y102667I-389J390D01*
G01X944258Y101358D02*
G03X944800Y102667I-1310J1309D01*
G01X942980Y101919D02*
X943338Y102278D01*
G01X943899Y100999D02*
X944258Y101358D01*
G01X942437Y100610D02*
G02X942980Y101919I1852J-1D01*
G01X943737Y100609D02*
G02X943899Y100999I552J-1D01*
G01X942437Y96293D02*
Y100610D01*
G01X943737Y96293D02*
Y100609D01*
G01X941755Y94649D02*
G03X942437Y96293I-1644J1645D01*
G01X942675Y93729D02*
G03X943737Y96293I-2564J2564D01*
G01X941768Y92822D02*
X942675Y93729D01*
G01X958275Y109159D02*
X956967Y110467D01*
G01X959575Y109698D02*
X957897Y111376D01*
G01X959575Y109698D02*
X957897Y111376D01*
G01X958275Y109159D02*
X956967Y110467D01*
G01X951849Y113569D02*
Y114119D01*
G01X950549Y113030D02*
Y114119D01*
G01X953250Y112168D02*
X951849Y113569D01*
G01X951950Y111629D02*
X950549Y113030D01*
G01D02*
Y114119D01*
G01X951849Y113569D02*
Y114119D01*
G01X951950Y111629D02*
X950549Y113030D01*
G01X953250Y112168D02*
X951849Y113569D01*
G01X974100Y272695D02*
Y264500D01*
G01X977282Y290746D02*
X974100Y272695D01*
G01D02*
Y264500D01*
G01X977282Y290746D02*
X974100Y272695D01*
G01X970197D02*
Y264697D01*
G01X971497Y272581D02*
Y264697D01*
G01X973346Y290559D02*
X970197Y272695D01*
G01X974667Y290559D02*
X971497Y272581D01*
G01D02*
Y264697D01*
G01X970197Y272695D02*
Y264697D01*
G01X974667Y290559D02*
X971497Y272581D01*
G01X973346Y290559D02*
X970197Y272695D01*
G01X962323Y281304D02*
Y264500D01*
G01X963623Y281190D02*
Y264500D01*
G01X966297Y276986D02*
Y264497D01*
G01X967597Y276872D02*
Y264497D01*
G01X963623Y281190D02*
Y264500D01*
G01X962323Y281304D02*
Y264500D01*
G01X967597Y276872D02*
Y264497D01*
G01X966297Y276986D02*
Y264497D01*
G01X958423Y264500D02*
Y285043D01*
G01X959723Y264500D02*
Y284929D01*
G01Y264500D02*
Y284929D01*
G01X958423Y264500D02*
Y285043D01*
G01X954500Y283849D02*
Y264500D01*
G01X955800Y283963D02*
Y264500D01*
G01Y283963D02*
Y264500D01*
G01X954500Y283849D02*
Y264500D01*
G01X950400Y264700D02*
Y280566D01*
G01X951700Y264700D02*
Y280680D01*
G01Y264700D02*
Y280680D01*
G01X950400Y264700D02*
Y280566D01*
G01X972779Y316282D02*
X977282Y290746D01*
G01X972779Y316282D02*
X977282Y290746D01*
G01X968865Y315974D02*
X973346Y290559D01*
G01X970186Y315974D02*
X974667Y290559D01*
G01X970186Y315974D02*
X974667Y290559D01*
G01X968865Y315974D02*
X973346Y290559D01*
G01X963868Y290072D02*
X962323Y281304D01*
G01X965189Y290072D02*
X963623Y281190D01*
G01X958534Y320321D02*
X963868Y290072D01*
G01X959855Y320321D02*
X965189Y290072D01*
G01X968679Y290500D02*
X966297Y276986D01*
G01X970000Y290500D02*
X967597Y276872D01*
G01X963301Y321000D02*
X968679Y290500D01*
G01X964622Y321000D02*
X970000Y290500D01*
G01X965189Y290072D02*
X963623Y281190D01*
G01X963868Y290072D02*
X962323Y281304D01*
G01X959855Y320321D02*
X965189Y290072D01*
G01X958534Y320321D02*
X963868Y290072D01*
G01X970000Y290500D02*
X967597Y276872D01*
G01X968679Y290500D02*
X966297Y276986D01*
G01X964622Y321000D02*
X970000Y290500D01*
G01X963301Y321000D02*
X968679Y290500D01*
G01X959236Y289661D02*
X953814Y320411D01*
G01X960557Y289661D02*
X955135Y320411D01*
G01X958423Y285043D02*
X959236Y289661D01*
G01X959723Y284929D02*
X960557Y289661D01*
G01D02*
X955135Y320411D01*
G01X959236Y289661D02*
X953814Y320411D01*
G01X959723Y284929D02*
X960557Y289661D01*
G01X958423Y285043D02*
X959236Y289661D01*
G01X948578Y317428D02*
X954500Y283849D01*
G01X949899Y317428D02*
X955800Y283963D01*
G01X949899Y317428D02*
X955800Y283963D01*
G01X948578Y317428D02*
X954500Y283849D01*
G01X950400Y280566D02*
X944535Y313821D01*
G01X951700Y280680D02*
X945856Y313821D01*
G01X951700Y280680D02*
X945856Y313821D01*
G01X950400Y280566D02*
X944535Y313821D01*
G01X944460Y297882D02*
X941590Y314161D01*
G01X944460Y297882D02*
X941590Y314161D01*
G01X974100Y316282D02*
X978603Y290746D01*
G01X979140Y352359D02*
X972779Y316282D01*
G01X980461Y352359D02*
X974100Y316282D01*
G01D02*
X978603Y290746D01*
G01X980461Y352359D02*
X974100Y316282D01*
G01X979140Y352359D02*
X972779Y316282D01*
G01X975161Y351680D02*
X968865Y315974D01*
G01X976482Y351680D02*
X970186Y315974D01*
G01X976482Y351680D02*
X970186Y315974D01*
G01X975161Y351680D02*
X968865Y315974D01*
G01X963679Y349500D02*
X958534Y320321D01*
G01X965000Y349500D02*
X959855Y320321D01*
G01X968679Y351500D02*
X963301Y321000D01*
G01X970000Y351500D02*
X964622Y321000D01*
G01X965000Y349500D02*
X959855Y320321D01*
G01X963679Y349500D02*
X958534Y320321D01*
G01X970000Y351500D02*
X964622Y321000D01*
G01X968679Y351500D02*
X963301Y321000D01*
G01X953814Y320411D02*
X958994Y349788D01*
G01X955135Y320411D02*
X960315Y349786D01*
G01X955135Y320411D02*
X960315Y349786D01*
G01X953814Y320411D02*
X958994Y349788D01*
G01X954899Y353224D02*
X948578Y317428D01*
G01X956220Y353224D02*
X949899Y317428D01*
G01X956220Y353224D02*
X949899Y317428D01*
G01X954899Y353224D02*
X948578Y317428D01*
G01X944535Y313821D02*
X951179Y351500D01*
G01X945856Y313821D02*
X952500Y351500D01*
G01X945856Y313821D02*
X952500Y351500D01*
G01X944535Y313821D02*
X951179Y351500D01*
G01X941590Y314161D02*
X947953Y350250D01*
G01X941590Y314161D02*
X947953Y350250D01*
G01X958225Y470973D02*
X979140Y352359D01*
G01X958225Y470973D02*
X979140Y352359D01*
G01X955431Y463577D02*
X975161Y351680D01*
G01X956662Y464087D02*
X976482Y351680D01*
G01X956662Y464087D02*
X976482Y351680D01*
G01X955431Y463577D02*
X975161Y351680D01*
G01X943981Y461213D02*
X963679Y349500D01*
G01X945212Y461723D02*
X965000Y349500D01*
G01X949392Y460884D02*
X968679Y351500D01*
G01X950623Y461394D02*
X970000Y351500D01*
G01X945212Y461723D02*
X965000Y349500D01*
G01X943981Y461213D02*
X963679Y349500D01*
G01X950623Y461394D02*
X970000Y351500D01*
G01X949392Y460884D02*
X968679Y351500D01*
G01X982655Y352705D02*
X960833Y476464D01*
G01X983976Y352705D02*
X962064Y476974D01*
G01X983976Y352705D02*
X962064Y476974D01*
G01X982655Y352705D02*
X960833Y476464D01*
G01X959456Y471483D02*
X980461Y352359D01*
G01X959456Y471483D02*
X980461Y352359D01*
G01X964713Y479920D02*
X988679Y344000D01*
G01X965944Y480430D02*
X990000Y344000D01*
G01X965944Y480430D02*
X990000Y344000D01*
G01X964713Y479920D02*
X988679Y344000D01*
G01X993373Y344876D02*
X968863Y483879D01*
G01X970094Y484389D02*
X994694Y344876D01*
G01X970094Y484389D02*
X994694Y344876D01*
G01X993373D02*
X968863Y483879D01*
G01X1012639Y73074D02*
X997600Y75600D01*
G01X1011108Y67974D02*
X996069Y70500D01*
G01X1011088Y69296D02*
X996695Y71714D01*
G01X1009711Y64096D02*
X995318Y66514D01*
G01X1009731Y62774D02*
X994692Y65300D01*
G01X1007109Y58962D02*
X991403Y61600D01*
G01X1007089Y60284D02*
X992029Y62814D01*
G01X1019639Y61468D02*
X1007109Y58962D01*
G01X1019660Y62799D02*
X1007089Y60284D01*
G01X1012639Y73074D02*
X997600Y75600D01*
G01X1011088Y69296D02*
X996695Y71714D01*
G01X1011108Y67974D02*
X996069Y70500D01*
G01X1009731Y62774D02*
X994692Y65300D01*
G01X1009711Y64096D02*
X995318Y66514D01*
G01X1007089Y60284D02*
X992029Y62814D01*
G01X1007109Y58962D02*
X991403Y61600D01*
G01X1019660Y62799D02*
X1007089Y60284D01*
G01X1019639Y61468D02*
X1007109Y58962D01*
G01X1006697Y56282D02*
X988832Y59433D01*
G01X1006697Y54961D02*
X988202Y58223D01*
G01X1011667Y57159D02*
X1006697Y56282D01*
G01X1011893Y55878D02*
X1006697Y54961D01*
G01D02*
X988202Y58223D01*
G01X1006697Y56282D02*
X988832Y59433D01*
G01X1011893Y55878D02*
X1006697Y54961D01*
G01X1011667Y57159D02*
X1006697Y56282D01*
G01X987351Y55262D02*
X975172Y67441D01*
G01X988360Y54556D02*
X987351Y55262D01*
G01X987850Y53325D02*
X986512Y54262D01*
G01X990040Y54259D02*
X988360Y54556D01*
G01X989815Y52979D02*
X987850Y53325D01*
G01X1033105Y46667D02*
X990040Y54259D01*
G01X1032595Y45436D02*
X989815Y52979D01*
G01X987351Y55262D02*
X975172Y67441D01*
G01X987850Y53325D02*
X986512Y54262D01*
G01X988360Y54556D02*
X987351Y55262D01*
G01X989815Y52979D02*
X987850Y53325D01*
G01X990040Y54259D02*
X988360Y54556D01*
G01X1032595Y45436D02*
X989815Y52979D01*
G01X1033105Y46667D02*
X990040Y54259D01*
G01X1002138Y97600D02*
X985200Y114538D01*
G01X1002760Y98817D02*
X986500Y115077D01*
G01X1017021Y95204D02*
X1002138Y97600D01*
G01X1016996Y96525D02*
X1002760Y98817D01*
G01X997996Y93404D02*
X980627Y110773D01*
G01X998624Y94616D02*
X983216Y110024D01*
G01X1015267Y90427D02*
X997996Y93404D01*
G01X1015249Y91750D02*
X998624Y94616D01*
G01X998539Y89600D02*
X977718Y110420D01*
G01X997911Y88388D02*
X976418Y109881D01*
G01X1013039Y87100D02*
X998539Y89600D01*
G01X1013057Y85777D02*
X997911Y88388D01*
G01X1002760Y98817D02*
X986500Y115077D01*
G01X1002138Y97600D02*
X985200Y114538D01*
G01X1016996Y96525D02*
X1002760Y98817D01*
G01X1017021Y95204D02*
X1002138Y97600D01*
G01X997996Y93404D02*
X980627Y110773D01*
G01X998624Y94616D02*
X983216Y110024D01*
G01X997996Y93404D02*
X980627Y110773D01*
G01X1015249Y91750D02*
X998624Y94616D01*
G01X1015267Y90427D02*
X997996Y93404D01*
G01X997911Y88388D02*
X976418Y109881D01*
G01X998539Y89600D02*
X977718Y110420D01*
G01X1013057Y85777D02*
X997911Y88388D01*
G01X1013039Y87100D02*
X998539Y89600D01*
G01X999349Y82214D02*
X1013742Y79796D01*
G01X1013762Y78474D02*
X998723Y81000D01*
G01X974836Y114345D02*
Y106726D01*
G01X1012619Y74396D02*
X998226Y76814D01*
G01X974836Y114345D02*
Y106726D01*
G01X1013762Y78474D02*
X998723Y81000D01*
G01X999349Y82214D02*
X1013742Y79796D01*
G01X1012619Y74396D02*
X998226Y76814D01*
G01X985200Y116900D02*
X982800Y119300D01*
G01X986500Y117439D02*
X985200Y118739D01*
G01Y114538D02*
Y116900D01*
G01X986500Y115077D02*
Y117439D01*
G01X980627Y110773D02*
G02X979033Y114278I4512J4167D01*
G01X981566Y111673D02*
G02X980326Y114418I3573J3266D01*
G01X983216Y110024D02*
X981566Y111673D01*
G01X977813Y117394D02*
G02X978049Y118373I6917J-1150D01*
G01X976530Y117607D02*
G02X976810Y118768I8200J-1363D01*
G01X976418Y116244D02*
G02X976530Y117607I8313J3D01*
G01X977718Y116244D02*
G02X977813Y117394I7012J0D01*
G01X976418Y116244D02*
G02X976530Y117607I8313J3D01*
G01X977718Y110420D02*
Y116244D01*
G01X976418Y109881D02*
Y116244D01*
G01X986500Y117439D02*
X985200Y118739D01*
G01Y116900D02*
X982800Y119300D01*
G01X986500Y115077D02*
Y117439D01*
G01X985200Y114538D02*
Y116900D01*
G01X981566Y111673D02*
G02X980326Y114418I3573J3266D01*
G01X980627Y110773D02*
G02X979033Y114278I4512J4167D01*
G01X983216Y110024D02*
X981566Y111673D01*
G01X976530Y117607D02*
G02X976810Y118768I8200J-1363D01*
G01X977813Y117394D02*
G02X978049Y118373I6917J-1150D01*
G01X976418Y116244D02*
G02X976530Y117607I8313J3D01*
G01X977813Y117394D02*
G02X978049Y118373I6917J-1150D01*
G01X977718Y116244D02*
G02X977813Y117394I7012J0D01*
G01X976418Y109881D02*
Y116244D01*
G01X977718Y110420D02*
Y116244D01*
G01X1005648Y185479D02*
Y184389D01*
G01X1006948Y184940D02*
Y184390D01*
G01X1007979Y187810D02*
X1005648Y185479D01*
G01X1008518Y186510D02*
X1006948Y184940D01*
G01X1025039Y187810D02*
X1007979D01*
G01X1006948Y184940D02*
Y184390D01*
G01X1005648Y185479D02*
Y184389D01*
G01X1008518Y186510D02*
X1006948Y184940D01*
G01X1007979Y187810D02*
X1005648Y185479D01*
G01X1025039Y187810D02*
X1007979D01*
G01X997850Y273034D02*
X1000383Y287410D01*
G01X1001629Y286986D02*
X999150Y272920D01*
G01X997850Y264926D02*
Y273034D01*
G01X999150Y272920D02*
Y264780D01*
G01X1005700Y272695D02*
X1007455Y282656D01*
G01X1008686Y282146D02*
X1007000Y272581D01*
G01X1005700Y264500D02*
Y272695D01*
G01X1007000Y272581D02*
Y264500D01*
G01X995201Y272581D02*
Y264601D01*
G01X993901Y272695D02*
Y264601D01*
G01X1000013Y299873D02*
X995201Y272581D01*
G01X998771Y300317D02*
X993901Y272695D01*
G01X999150Y272920D02*
Y264780D01*
G01X997850Y264926D02*
Y273034D01*
G01X1001629Y286986D02*
X999150Y272920D01*
G01X997850Y273034D02*
X1000383Y287410D01*
G01X1003000Y272581D02*
Y264500D01*
G01X1001700Y272695D02*
Y264500D01*
G01X1005259Y285393D02*
X1003000Y272581D01*
G01X1004028Y285903D02*
X1001700Y272695D01*
G01X1007000Y272581D02*
Y264500D01*
G01X1005700D02*
Y272695D01*
G01X1008686Y282146D02*
X1007000Y272581D01*
G01X1005700Y272695D02*
X1007455Y282656D01*
G01X993901Y272695D02*
Y264601D01*
G01X995201Y272581D02*
Y264601D01*
G01X998771Y300317D02*
X993901Y272695D01*
G01X1000013Y299873D02*
X995201Y272581D01*
G01X1001700Y272695D02*
Y264500D01*
G01X1003000Y272581D02*
Y264500D01*
G01X1004028Y285903D02*
X1001700Y272695D01*
G01X1005259Y285393D02*
X1003000Y272581D01*
G01X978100Y272695D02*
X981141Y289947D01*
G01X979400Y272581D02*
X982462Y289947D01*
G01X978100Y264600D02*
Y272695D01*
G01X979400Y264600D02*
Y272581D01*
G01X985900Y273734D02*
Y264500D01*
G01X987200Y273620D02*
Y264500D01*
G01X988679Y289500D02*
X985900Y273734D01*
G01X990000Y289500D02*
X987200Y273620D01*
G01X989884Y272695D02*
X992786Y289157D01*
G01X994107D02*
X991184Y272581D01*
G01X989884Y264584D02*
Y272695D01*
G01X991184Y272581D02*
Y264584D01*
G01X979400Y272581D02*
X982462Y289947D01*
G01X978100Y272695D02*
X981141Y289947D01*
G01X979400Y264600D02*
Y272581D01*
G01X978100Y264600D02*
Y272695D01*
G01X987200Y273620D02*
Y264500D01*
G01X985900Y273734D02*
Y264500D01*
G01X990000Y289500D02*
X987200Y273620D01*
G01X988679Y289500D02*
X985900Y273734D01*
G01X991184Y272581D02*
Y264584D01*
G01X989884D02*
Y272695D01*
G01X994107Y289157D02*
X991184Y272581D01*
G01X989884Y272695D02*
X992786Y289157D01*
G01X975400Y272581D02*
Y264500D01*
G01X978603Y290746D02*
X975400Y272581D01*
G01D02*
Y264500D01*
G01X978603Y290746D02*
X975400Y272581D01*
G01X1004389Y297126D02*
X1030328Y334175D01*
G01X1031559Y333665D02*
X1005537Y296499D01*
G01X1000401Y287420D02*
X1004389Y297126D01*
G01X1005537Y296499D02*
X1001629Y286986D01*
G01X1007455Y282656D02*
X1061269Y359510D01*
G01X1024932Y352834D02*
X1000013Y299873D01*
G01X1023681Y353231D02*
X998804Y300360D01*
G01X1005537Y296499D02*
X1001629Y286986D01*
G01X1000401Y287420D02*
X1004389Y297126D01*
G01X1031559Y333665D02*
X1005537Y296499D01*
G01X1004389Y297126D02*
X1030328Y334175D01*
G01X1057500Y360000D02*
X1005259Y285393D01*
G01X1056269Y360510D02*
X1004028Y285903D01*
G01X1007455Y282656D02*
X1061269Y359510D01*
G01X1023681Y353231D02*
X998804Y300360D01*
G01X1024932Y352834D02*
X1000013Y299873D01*
G01X1056269Y360510D02*
X1004028Y285903D01*
G01X1057500Y360000D02*
X1005259Y285393D01*
G01X981141Y289947D02*
X976365Y317033D01*
G01X982462Y289947D02*
X977686Y317033D01*
G01X983874Y316752D02*
X988679Y289500D01*
G01X985195Y316752D02*
X990000Y289500D01*
G01X992786Y289157D02*
X988167Y315351D01*
G01X989488D02*
X994107Y289157D01*
G01X982462Y289947D02*
X977686Y317033D01*
G01X981141Y289947D02*
X976365Y317033D01*
G01X985195Y316752D02*
X990000Y289500D01*
G01X983874Y316752D02*
X988679Y289500D01*
G01X989488Y315351D02*
X994107Y289157D01*
G01X992786D02*
X988167Y315351D01*
G01X976365Y317033D02*
X982655Y352705D01*
G01X977686Y317033D02*
X983976Y352705D01*
G01X988679Y344000D02*
X983874Y316752D01*
G01X990000Y344000D02*
X985195Y316752D01*
G01X988167Y315351D02*
X993373Y344876D01*
G01X994694D02*
X989488Y315351D01*
G01X977686Y317033D02*
X983976Y352705D01*
G01X976365Y317033D02*
X982655Y352705D01*
G01X990000Y344000D02*
X985195Y316752D01*
G01X988679Y344000D02*
X983874Y316752D01*
G01X994694Y344876D02*
X989488Y315351D01*
G01X988167D02*
X993373Y344876D01*
G01X1047608Y36512D02*
X1033105Y46667D01*
G01X1039593Y40537D02*
X1032595Y45436D01*
G01X1046588Y35639D02*
X1039593Y40537D01*
G01D02*
X1032595Y45436D01*
G01X1047608Y36512D02*
X1033105Y46667D01*
G01X1046588Y35639D02*
X1039593Y40537D01*
G01X1047608Y36512D02*
X1033105Y46667D01*
G01X1025139Y75574D02*
X1012639Y73074D01*
G01X1037639D02*
X1025139Y75574D01*
G01X1048642Y75275D02*
X1037639Y73074D01*
G01X1023608Y70474D02*
X1011108Y67974D01*
G01X1023608Y71800D02*
X1011088Y69296D01*
G01X1036108Y67974D02*
X1023608Y70474D01*
G01X1036108Y69300D02*
X1023608Y71800D01*
G01X1048608Y70474D02*
X1036108Y67974D01*
G01X1048608Y71800D02*
X1036108Y69300D01*
G01X1022231Y66600D02*
X1009711Y64096D01*
G01X1022231Y65274D02*
X1009731Y62774D01*
G01X1034731Y64100D02*
X1022231Y66600D01*
G01X1034731Y62774D02*
X1022231Y65274D01*
G01X1047231Y66600D02*
X1034731Y64100D01*
G01X1047231Y65274D02*
X1034731Y62774D01*
G01X1039280Y56881D02*
X1019639Y61468D01*
G01X1039937Y58063D02*
X1019660Y62799D01*
G01X1044901Y51259D02*
X1039280Y56881D01*
G01X1045531Y52469D02*
X1039937Y58063D01*
G01X1025139Y75574D02*
X1012639Y73074D01*
G01X1025139Y75574D02*
X1012639Y73074D01*
G01X1037639D02*
X1025139Y75574D01*
G01X1048642Y75275D02*
X1037639Y73074D01*
G01X1023608Y71800D02*
X1011088Y69296D01*
G01X1023608Y70474D02*
X1011108Y67974D01*
G01X1036108Y69300D02*
X1023608Y71800D01*
G01X1036108Y67974D02*
X1023608Y70474D01*
G01X1048608Y71800D02*
X1036108Y69300D01*
G01X1048608Y70474D02*
X1036108Y67974D01*
G01X1022231Y65274D02*
X1009731Y62774D01*
G01X1022231Y66600D02*
X1009711Y64096D01*
G01X1034731Y62774D02*
X1022231Y65274D01*
G01X1034731Y64100D02*
X1022231Y66600D01*
G01X1047231Y65274D02*
X1034731Y62774D01*
G01X1047231Y66600D02*
X1034731Y64100D01*
G01X1039937Y58063D02*
X1019660Y62799D01*
G01X1039280Y56881D02*
X1019639Y61468D01*
G01X1045531Y52469D02*
X1039937Y58063D01*
G01X1044901Y51259D02*
X1039280Y56881D01*
G01X1014836Y57718D02*
X1011667Y57159D01*
G01X1015062Y56437D02*
X1011893Y55878D01*
G01X1015319Y57803D02*
X1014836Y57718D01*
G01X1015062Y56437D02*
X1011893Y55878D01*
G01X1017000Y56779D02*
X1015062Y56437D01*
G01X1017000Y58100D02*
X1015319Y57803D01*
G01X1017000Y56779D02*
X1015062Y56437D01*
G01X1037213Y54536D02*
X1017000Y58100D01*
G01X1036583Y53326D02*
X1017000Y56779D01*
G01X1045071Y46678D02*
X1037213Y54536D01*
G01X1044396Y45513D02*
X1036583Y53326D01*
G01X1015062Y56437D02*
X1011893Y55878D01*
G01X1014836Y57718D02*
X1011667Y57159D01*
G01X1015319Y57803D02*
X1014836Y57718D01*
G01X1017000Y56779D02*
X1015062Y56437D01*
G01X1015319Y57803D02*
X1014836Y57718D01*
G01X1017000Y58100D02*
X1015319Y57803D01*
G01X1036583Y53326D02*
X1017000Y56779D01*
G01X1037213Y54536D02*
X1017000Y58100D01*
G01X1044396Y45513D02*
X1036583Y53326D01*
G01X1045071Y46678D02*
X1037213Y54536D01*
G01X1029267Y97653D02*
X1017021Y95204D01*
G01X1029252Y98976D02*
X1016996Y96525D01*
G01X1043725Y95102D02*
X1029267Y97653D01*
G01X1043725Y96423D02*
X1029252Y98976D01*
G01X1027753Y92922D02*
X1015267Y90427D01*
G01X1027753Y94248D02*
X1015249Y91750D01*
G01X1040249Y90424D02*
X1027753Y92922D01*
G01X1040251Y91750D02*
X1027753Y94248D01*
G01X1079667Y98231D02*
X1040249Y90424D01*
G01X1079653Y99554D02*
X1040251Y91750D01*
G01X1025541Y89599D02*
X1013039Y87100D01*
G01X1025541Y88273D02*
X1013057Y85777D01*
G01X1038039Y87100D02*
X1025541Y89599D01*
G01X1038039Y85774D02*
X1025541Y88273D01*
G01X1050654Y89623D02*
X1038039Y87100D01*
G01X1050669Y88300D02*
X1038039Y85774D01*
G01X1029252Y98976D02*
X1016996Y96525D01*
G01X1029267Y97653D02*
X1017021Y95204D01*
G01X1043725Y96423D02*
X1029252Y98976D01*
G01X1043725Y95102D02*
X1029267Y97653D01*
G01X1027753Y94248D02*
X1015249Y91750D01*
G01X1027753Y92922D02*
X1015267Y90427D01*
G01X1040251Y91750D02*
X1027753Y94248D01*
G01X1040249Y90424D02*
X1027753Y92922D01*
G01X1079653Y99554D02*
X1040251Y91750D01*
G01X1079667Y98231D02*
X1040249Y90424D01*
G01X1025541Y88273D02*
X1013057Y85777D01*
G01X1025541Y89599D02*
X1013039Y87100D01*
G01X1038039Y85774D02*
X1025541Y88273D01*
G01X1038039Y87100D02*
X1025541Y89599D01*
G01X1050669Y88300D02*
X1038039Y85774D01*
G01X1050654Y89623D02*
X1038039Y87100D01*
G01X1038762Y79800D02*
X1051262Y82300D01*
G01Y80974D02*
X1038762Y78474D01*
G01X1026262Y82300D02*
X1038762Y79800D01*
G01Y78474D02*
X1026262Y80974D01*
G01X1013742Y79796D02*
X1026262Y82300D01*
G01X1020011Y79724D02*
X1013762Y78474D01*
G01X1026262Y80974D02*
X1020011Y79724D01*
G01X1018635Y75599D02*
X1012619Y74396D01*
G01X1025139Y76900D02*
X1018635Y75599D01*
G01X1037639Y74400D02*
X1025139Y76900D01*
G01X1048642Y76601D02*
X1037639Y74400D01*
G01X1020011Y79724D02*
X1013762Y78474D01*
G01X1013742Y79796D02*
X1026262Y82300D01*
G01Y80974D02*
X1020011Y79724D01*
G01X1013742Y79796D02*
X1026262Y82300D01*
G01X1038762Y78474D02*
X1026262Y80974D01*
G01Y82300D02*
X1038762Y79800D01*
G01X1051262Y80974D02*
X1038762Y78474D01*
G01Y79800D02*
X1051262Y82300D01*
G01X1018635Y75599D02*
X1012619Y74396D01*
G01X1025139Y76900D02*
X1018635Y75599D01*
G01X1037639Y74400D02*
X1025139Y76900D01*
G01X1048642Y76601D02*
X1037639Y74400D01*
G01X1021517Y141444D02*
X1018550D01*
G01X1023457Y141343D02*
X1022056Y142744D01*
G01X1022918Y140043D02*
X1021517Y141444D01*
G01X1037289Y141343D02*
X1023457D01*
G01X1037481Y140043D02*
X1022918D01*
G01X1043344Y143171D02*
X1037289Y141343D01*
G01X1049957Y143809D02*
X1037481Y140043D01*
G01X1049957Y143809D02*
X1037481Y140043D01*
G01X1035401Y129294D02*
X1047380Y131690D01*
G01X1047365Y133013D02*
X1035272Y130594D01*
G01X1022776Y129294D02*
X1035401D01*
G01X1035272Y130594D02*
X1022776D01*
G01X1035197Y124793D02*
X1022407D01*
G01Y126093D02*
X1035066D01*
G01X1038842Y125522D02*
X1035197Y124793D01*
G01X1035066Y126093D02*
X1038815Y126843D01*
G01X1083122Y118504D02*
X1038842Y125522D01*
G01X1038815Y126843D02*
X1083326Y119789D01*
G01X1021517Y141444D02*
X1018550D01*
G01X1022918Y140043D02*
X1021517Y141444D01*
G01X1023457Y141343D02*
X1022056Y142744D01*
G01X1037481Y140043D02*
X1022918D01*
G01X1037289Y141343D02*
X1023457D01*
G01X1049957Y143809D02*
X1037481Y140043D01*
G01X1043344Y143171D02*
X1037289Y141343D01*
G01X1020000Y135400D02*
X1018407Y136993D01*
G01X1020540Y136700D02*
X1019327Y137913D01*
G01X1039400Y135400D02*
X1020000D01*
G01X1039271Y136700D02*
X1020540D01*
G01X1052057Y137930D02*
X1039400Y135400D01*
G01X1052042Y139253D02*
X1039271Y136700D01*
G01X1035272Y130594D02*
X1022776D01*
G01Y129294D02*
X1035401D01*
G01X1047365Y133013D02*
X1035272Y130594D01*
G01X1035401Y129294D02*
X1047380Y131690D01*
G01X1038815Y126843D02*
X1083326Y119789D01*
G01X1083122Y118504D02*
X1038842Y125522D01*
G01X1035066Y126093D02*
X1038815Y126843D01*
G01X1038842Y125522D02*
X1035197Y124793D01*
G01X1022407Y126093D02*
X1035066D01*
G01X1035197Y124793D02*
X1022407D01*
G01X1020540Y136700D02*
X1019327Y137913D01*
G01X1020000Y135400D02*
X1018407Y136993D01*
G01X1039271Y136700D02*
X1020540D01*
G01X1039400Y135400D02*
X1020000D01*
G01X1052042Y139253D02*
X1039271Y136700D01*
G01X1052057Y137930D02*
X1039400Y135400D01*
G01X1025154Y173860D02*
X1022728D01*
G01X1025268Y172560D02*
X1023022D01*
G01X1070271Y181814D02*
X1025154Y173860D01*
G01X1070801Y180587D02*
X1025268Y172560D01*
G01X1025153Y169960D02*
X1070718Y177994D01*
G01X1025267Y168660D02*
X1071228Y176763D01*
G01X1022340Y169960D02*
X1025153D01*
G01X1022340Y168660D02*
X1025267D01*
G01X1030798Y159000D02*
X1020700D01*
G01X1030588Y160300D02*
X1020800D01*
G01X1062657Y169538D02*
X1030798Y159000D01*
G01X1062548Y170872D02*
X1030588Y160300D01*
G01X1031044Y154351D02*
X1023700D01*
G01X1030851Y155651D02*
X1023750D01*
G01X1063149Y164070D02*
X1031044Y154351D01*
G01X1063084Y165409D02*
X1030851Y155651D01*
G01X1034735Y148968D02*
X1022000D01*
G01X1021268Y150268D02*
X1034524D01*
G01X1065621Y159183D02*
X1034735Y148968D01*
G01X1034524Y150268D02*
X1065539Y160526D01*
G01X1035095Y145001D02*
X1022300D01*
G01X1034901Y146301D02*
X1022300D01*
G01X1067306Y154786D02*
X1035095Y145001D01*
G01X1067239Y156126D02*
X1034901Y146301D01*
G01X1025268Y172560D02*
X1023022D01*
G01X1025154Y173860D02*
X1022728D01*
G01X1070801Y180587D02*
X1025268Y172560D01*
G01X1070271Y181814D02*
X1025154Y173860D01*
G01X1025267Y168660D02*
X1071228Y176763D01*
G01X1025153Y169960D02*
X1070718Y177994D01*
G01X1022340Y168660D02*
X1025267D01*
G01X1022340Y169960D02*
X1025153D01*
G01X1030588Y160300D02*
X1020800D01*
G01X1030798Y159000D02*
X1020700D01*
G01X1062548Y170872D02*
X1030588Y160300D01*
G01X1062657Y169538D02*
X1030798Y159000D01*
G01X1030851Y155651D02*
X1023750D01*
G01X1031044Y154351D02*
X1023700D01*
G01X1063084Y165409D02*
X1030851Y155651D01*
G01X1063149Y164070D02*
X1031044Y154351D01*
G01X1034524Y150268D02*
X1065539Y160526D01*
G01X1065621Y159183D02*
X1034735Y148968D01*
G01X1021268Y150268D02*
X1034524D01*
G01X1034735Y148968D02*
X1022000D01*
G01X1034901Y146301D02*
X1022300D01*
G01X1035095Y145001D02*
X1022300D01*
G01X1067239Y156126D02*
X1034901Y146301D01*
G01X1067306Y154786D02*
X1035095Y145001D01*
G01X1022056Y142744D02*
X1018600D01*
G01X1022056D02*
X1018600D01*
G01X1041724Y208100D02*
X1052500Y210000D01*
G01X1022600Y208100D02*
X1041724D01*
G01X1025153Y201400D02*
X1022494D01*
G01X1025267Y200100D02*
X1022700D01*
G01X1055656Y206778D02*
X1025153Y201400D01*
G01X1056166Y205547D02*
X1025267Y200100D01*
G01X1025153Y197500D02*
X1058381Y203359D01*
G01X1025267Y196200D02*
X1058891Y202128D01*
G01X1022494Y197500D02*
X1025153D01*
G01X1022500Y196200D02*
X1025267D01*
G01X1025039Y193500D02*
X1060030Y199671D01*
G01X1025153Y192200D02*
X1060540Y198440D01*
G01X1022000Y193500D02*
X1025039D01*
G01X1022000Y192200D02*
X1025153D01*
G01Y186510D02*
X1008518D01*
G01X1062658Y194444D02*
X1025039Y187810D01*
G01X1063168Y193213D02*
X1025153Y186510D01*
G01Y181700D02*
X1022494D01*
G01X1025267Y180400D02*
X1022200D01*
G01X1065303Y188780D02*
X1025153Y181700D01*
G01X1065813Y187549D02*
X1025267Y180400D01*
G01X1041724Y208100D02*
X1052500Y210000D01*
G01X1022600Y208100D02*
X1041724D01*
G01X1025267Y200100D02*
X1022700D01*
G01X1025153Y201400D02*
X1022494D01*
G01X1056166Y205547D02*
X1025267Y200100D01*
G01X1055656Y206778D02*
X1025153Y201400D01*
G01X1025267Y196200D02*
X1058891Y202128D01*
G01X1025153Y197500D02*
X1058381Y203359D01*
G01X1022500Y196200D02*
X1025267D01*
G01X1022494Y197500D02*
X1025153D01*
G01Y192200D02*
X1060540Y198440D01*
G01X1025039Y193500D02*
X1060030Y199671D01*
G01X1022000Y192200D02*
X1025153D01*
G01X1022000Y193500D02*
X1025039D01*
G01X1025153Y186510D02*
X1008518D01*
G01X1063168Y193213D02*
X1025153Y186510D01*
G01X1062658Y194444D02*
X1025039Y187810D01*
G01X1025267Y180400D02*
X1022200D01*
G01X1025153Y181700D02*
X1022494D01*
G01X1065813Y187549D02*
X1025267Y180400D01*
G01X1065303Y188780D02*
X1025153Y181700D01*
G01Y177797D02*
X1022397D01*
G01X1025267Y176497D02*
X1022500D01*
G01X1067053Y185184D02*
X1025153Y177797D01*
G01X1067563Y183953D02*
X1025267Y176497D01*
G01D02*
X1022500D01*
G01X1025153Y177797D02*
X1022397D01*
G01X1067563Y183953D02*
X1025267Y176497D01*
G01X1067053Y185184D02*
X1025153Y177797D01*
G01X1023204Y241866D02*
X1049898Y260559D01*
G01X1024007Y240841D02*
X1050832Y259625D01*
G01X1022736Y241457D02*
X1023204Y241866D01*
G01X1023592Y240478D02*
X1024007Y240841D01*
G01X1035501Y241096D02*
X1057500Y256500D01*
G01X1058434Y255566D02*
X1036211Y240006D01*
G01X1023263Y233691D02*
X1035501Y241096D01*
G01X1036211Y240006D02*
X1023936Y232578D01*
G01X1033354Y230591D02*
X1062500Y251000D01*
G01X1063434Y250066D02*
X1033864Y229360D01*
G01X1024329Y229000D02*
X1033354Y230591D01*
G01X1033864Y229360D02*
X1024443Y227700D01*
G01X1022000Y229000D02*
X1024329D01*
G01X1024443Y227700D02*
X1022000D01*
G01X1040662Y227744D02*
X1068390Y247159D01*
G01X1041172Y226513D02*
X1069324Y246225D01*
G01X1025100Y225000D02*
X1040662Y227744D01*
G01X1025214Y223700D02*
X1041172Y226513D01*
G01X1022894Y225000D02*
X1025100D01*
G01X1023000Y223700D02*
X1025214D01*
G01X1025153Y221000D02*
X1022894D01*
G01X1025267Y219700D02*
X1022600D01*
G01X1042746Y224102D02*
X1025153Y221000D01*
G01X1043256Y222871D02*
X1025267Y219700D01*
G01X1034473Y217203D02*
X1022894D01*
G01X1023000Y215903D02*
X1034587D01*
G01X1047500Y219500D02*
X1034473Y217203D01*
G01X1034587Y215903D02*
X1048010Y218269D01*
G01X1037977Y213200D02*
X1022894D01*
G01X1038091Y211900D02*
X1022600D01*
G01X1049490Y215231D02*
X1037977Y213200D01*
G01X1050000Y214000D02*
X1038091Y211900D01*
G01X1024007Y240841D02*
X1050832Y259625D01*
G01X1023204Y241866D02*
X1049898Y260559D01*
G01X1023592Y240478D02*
X1024007Y240841D01*
G01X1022736Y241457D02*
X1023204Y241866D01*
G01X1036211Y240006D02*
X1023936Y232578D01*
G01X1023263Y233691D02*
X1035501Y241096D01*
G01X1058434Y255566D02*
X1036211Y240006D01*
G01X1035501Y241096D02*
X1057500Y256500D01*
G01X1024443Y227700D02*
X1022000D01*
G01Y229000D02*
X1024329D01*
G01X1033864Y229360D02*
X1024443Y227700D01*
G01X1024329Y229000D02*
X1033354Y230591D01*
G01X1063434Y250066D02*
X1033864Y229360D01*
G01X1033354Y230591D02*
X1062500Y251000D01*
G01X1041172Y226513D02*
X1069324Y246225D01*
G01X1040662Y227744D02*
X1068390Y247159D01*
G01X1025214Y223700D02*
X1041172Y226513D01*
G01X1025100Y225000D02*
X1040662Y227744D01*
G01X1023000Y223700D02*
X1025214D01*
G01X1022894Y225000D02*
X1025100D01*
G01X1025267Y219700D02*
X1022600D01*
G01X1025153Y221000D02*
X1022894D01*
G01X1043256Y222871D02*
X1025267Y219700D01*
G01X1042746Y224102D02*
X1025153Y221000D01*
G01X1034587Y215903D02*
X1048010Y218269D01*
G01X1047500Y219500D02*
X1034473Y217203D01*
G01X1023000Y215903D02*
X1034587D01*
G01X1034473Y217203D02*
X1022894D01*
G01X1038091Y211900D02*
X1022600D01*
G01X1037977Y213200D02*
X1022894D01*
G01X1050000Y214000D02*
X1038091Y211900D01*
G01X1049490Y215231D02*
X1037977Y213200D01*
G01X1041610Y209400D02*
X1051990Y211231D01*
G01X1022600Y209400D02*
X1041610D01*
G01D02*
X1051990Y211231D01*
G01X1022600Y209400D02*
X1041610D01*
G01X1013600Y272695D02*
Y264700D01*
G01X1014900D02*
Y272581D01*
G01X1014045Y275225D02*
X1013600Y272695D01*
G01X1014900Y272581D02*
X1015276Y274715D01*
G01X1072165Y358233D02*
X1014045Y275225D01*
G01X1015276Y274715D02*
X1073396Y357723D01*
G01X1010900Y272581D02*
Y264500D01*
G01X1009600Y272695D02*
Y264500D01*
G01X1011864Y278044D02*
X1010900Y272581D01*
G01X1010633Y278554D02*
X1009600Y272695D01*
G01X1015276Y274715D02*
X1073396Y357723D01*
G01X1072165Y358233D02*
X1014045Y275225D01*
G01X1014900Y272581D02*
X1015276Y274715D01*
G01X1014045Y275225D02*
X1013600Y272695D01*
G01X1014900Y264700D02*
Y272581D01*
G01X1013600Y272695D02*
Y264700D01*
G01X1009600Y272695D02*
Y264500D01*
G01X1010900Y272581D02*
Y264500D01*
G01X1010633Y278554D02*
X1009600Y272695D01*
G01X1011864Y278044D02*
X1010900Y272581D01*
G01X1067500Y357500D02*
X1011864Y278044D01*
G01X1066269Y358010D02*
X1010633Y278554D01*
G01X1066269Y358010D02*
X1010633Y278554D01*
G01X1067500Y357500D02*
X1011864Y278044D01*
G01X1062500Y359000D02*
X1008686Y282146D01*
G01X1062500Y359000D02*
X1008686Y282146D01*
G01X1030328Y334175D02*
X1077321Y600690D01*
G01X1078642D02*
X1031559Y333665D01*
G01X1078642Y600690D02*
X1031559Y333665D01*
G01X1030328Y334175D02*
X1077321Y600690D01*
G01X1071600Y617500D02*
X1024932Y352834D01*
G01X1070279Y617500D02*
X1023681Y353231D01*
G01X1070279Y617500D02*
X1023681Y353231D01*
G01X1071600Y617500D02*
X1024932Y352834D01*
G01X1031497Y837446D02*
X1070279Y617500D01*
G01X1031497Y837446D02*
X1070279Y617500D01*
G01X1032818Y837445D02*
X1071600Y617500D01*
G01X1032818Y837445D02*
X1071600Y617500D01*
G01X1037264Y862662D02*
X1032818Y837445D01*
G01X1035964Y862779D02*
X1031497Y837446D01*
G01X1035964Y862779D02*
X1031497Y837446D01*
G01X1037264Y862662D02*
X1032818Y837445D01*
G01X1037264Y873200D02*
Y862662D01*
G01X1035964Y873200D02*
Y862779D01*
G01Y873200D02*
Y862779D01*
G01X1037264Y873200D02*
Y862662D01*
G01X1080424Y32213D02*
X1056470Y49219D01*
G01X1080733Y33588D02*
X1056984Y50449D01*
G01X1080733Y33588D02*
X1056984Y50449D01*
G01X1080424Y32213D02*
X1056470Y49219D01*
G01X1058543Y36687D02*
Y41701D01*
G01X1057243Y36148D02*
Y41162D01*
G01X1060113Y35117D02*
X1058543Y36687D01*
G01X1059574Y33817D02*
X1057243Y36148D01*
G01X1064729Y35117D02*
X1060113D01*
G01X1064771Y33817D02*
X1059574D01*
G01X1057243Y36148D02*
Y41162D01*
G01X1058543Y36687D02*
Y41701D01*
G01X1059574Y33817D02*
X1057243Y36148D01*
G01X1060113Y35117D02*
X1058543Y36687D01*
G01X1064771Y33817D02*
X1059574D01*
G01X1064729Y35117D02*
X1060113D01*
G01X1053506Y24498D02*
X1047608Y36512D01*
G01X1052407Y23786D02*
X1046588Y35639D01*
G01X1054637Y23138D02*
X1053507Y24497D01*
G01X1054027Y21838D02*
X1052407Y23786D01*
G01X1060250Y23138D02*
X1054637D01*
G01X1060250Y21838D02*
X1054027D01*
G01X1052407Y23786D02*
X1046588Y35639D01*
G01X1053506Y24498D02*
X1047608Y36512D01*
G01X1054027Y21838D02*
X1052407Y23786D01*
G01X1054637Y23138D02*
X1053507Y24497D01*
G01X1060250Y21838D02*
X1054027D01*
G01X1060250Y23138D02*
X1054637D01*
G01X1063423Y72319D02*
X1048642Y75275D01*
G01X1063423Y73645D02*
X1048642Y76601D01*
G01X1077579Y75150D02*
X1063423Y72319D01*
G01X1077564Y76473D02*
X1063423Y73645D01*
G01X1061108Y67974D02*
X1048608Y70474D01*
G01X1061108Y69300D02*
X1048608Y71800D01*
G01X1075220Y70796D02*
X1061108Y67974D01*
G01X1075205Y72119D02*
X1061108Y69300D01*
G01X1093331Y67602D02*
X1075220Y70796D01*
G01X1093841Y68833D02*
X1075205Y72119D01*
G01X1058261Y64394D02*
X1047231Y66600D01*
G01X1058261Y63068D02*
X1047231Y65274D01*
G01X1076256Y67993D02*
X1058261Y64394D01*
G01X1076271Y66670D02*
X1058261Y63068D01*
G01X1056470Y49219D02*
X1044901Y51259D01*
G01X1056984Y50449D02*
X1045531Y52469D01*
G01X1063423Y73645D02*
X1048642Y76601D01*
G01X1063423Y72319D02*
X1048642Y75275D01*
G01X1077564Y76473D02*
X1063423Y73645D01*
G01X1077579Y75150D02*
X1063423Y72319D01*
G01X1061108Y69300D02*
X1048608Y71800D01*
G01X1061108Y67974D02*
X1048608Y70474D01*
G01X1075205Y72119D02*
X1061108Y69300D01*
G01X1075220Y70796D02*
X1061108Y67974D01*
G01X1093841Y68833D02*
X1075205Y72119D01*
G01X1093331Y67602D02*
X1075220Y70796D01*
G01X1058261Y63068D02*
X1047231Y65274D01*
G01X1058261Y64394D02*
X1047231Y66600D01*
G01X1076271Y66670D02*
X1058261Y63068D01*
G01X1076256Y67993D02*
X1058261Y64394D01*
G01X1056984Y50449D02*
X1045531Y52469D01*
G01X1056470Y49219D02*
X1044901Y51259D01*
G01X1046664Y46247D02*
X1045071Y46678D01*
G01X1056046Y42359D02*
X1044396Y45513D01*
G01X1051200Y45019D02*
X1049608Y45450D01*
G01X1056046Y42359D02*
X1044396Y45513D01*
G01X1056721Y43524D02*
X1054144Y44221D01*
G01X1056046Y42359D02*
X1044396Y45513D01*
G01X1058163Y42082D02*
X1056721Y43524D01*
G01X1057243Y41162D02*
X1056046Y42359D01*
G01X1058162Y42082D02*
X1058163D01*
G01X1057243Y41162D02*
X1056046Y42359D01*
G01X1058543Y41701D02*
X1058162Y42082D01*
G01X1057243Y41162D02*
X1056046Y42359D01*
G01D02*
X1044396Y45513D01*
G01X1046664Y46247D02*
X1045071Y46678D01*
G01X1051200Y45019D02*
X1049608Y45450D01*
G01X1056721Y43524D02*
X1054144Y44221D01*
G01X1057243Y41162D02*
X1056046Y42359D01*
G01X1058163Y42082D02*
X1056721Y43524D01*
G01X1058162Y42082D02*
X1058163D01*
G01X1058543Y41701D02*
X1058162Y42082D01*
G01X1132672Y110788D02*
X1043725Y95102D01*
G01X1132672Y112109D02*
X1043725Y96423D01*
G01X1068916Y86403D02*
X1050654Y89623D01*
G01X1068916Y85082D02*
X1050669Y88300D01*
G01X1078546Y88101D02*
X1068916Y86403D01*
G01X1078546Y86780D02*
X1068916Y85082D01*
G01X1132672Y112109D02*
X1043725Y96423D01*
G01X1132672Y110788D02*
X1043725Y95102D01*
G01X1068916Y85082D02*
X1050669Y88300D01*
G01X1068916Y86403D02*
X1050654Y89623D01*
G01X1078546Y86780D02*
X1068916Y85082D01*
G01X1078546Y88101D02*
X1068916Y86403D01*
G01X1072790Y82912D02*
X1090984Y79704D01*
G01Y78383D02*
X1072805Y81589D01*
G01X1060495Y80453D02*
X1072790Y82912D01*
G01X1072805Y81589D02*
X1060495Y79127D01*
G01X1051262Y82300D02*
X1060495Y80453D01*
G01Y79127D02*
X1051262Y80974D01*
G01X1060495Y79127D02*
X1051262Y80974D01*
G01Y82300D02*
X1060495Y80453D01*
G01X1072805Y81589D02*
X1060495Y79127D01*
G01Y80453D02*
X1072790Y82912D01*
G01X1090984Y78383D02*
X1072805Y81589D01*
G01X1072790Y82912D02*
X1090984Y79704D01*
G01X1072790Y82912D02*
X1090984Y79704D01*
G01X1100446Y135037D02*
X1049893Y145148D01*
G01X1099923Y133815D02*
X1049957Y143809D01*
G01X1047380Y131690D02*
X1097382Y122872D01*
G01X1097892Y124103D02*
X1047365Y133013D01*
G01X1099923Y133815D02*
X1049957Y143809D01*
G01X1100446Y135037D02*
X1049893Y145148D01*
G01X1094805Y130397D02*
X1052057Y137930D01*
G01X1095276Y131635D02*
X1052042Y139253D01*
G01X1097892Y124103D02*
X1047365Y133013D01*
G01X1047380Y131690D02*
X1097382Y122872D01*
G01X1095276Y131635D02*
X1052042Y139253D01*
G01X1094805Y130397D02*
X1052057Y137930D01*
G01X1086673Y165769D02*
X1062657Y169538D01*
G01X1086655Y167088D02*
X1062548Y170872D01*
G01X1088068Y159086D02*
X1063149Y164070D01*
G01X1088068Y160412D02*
X1063084Y165409D01*
G01X1090539Y154200D02*
X1065621Y159183D01*
G01X1065539Y160526D02*
X1090539Y155526D01*
G01X1092239Y149800D02*
X1067306Y154786D01*
G01X1092239Y151126D02*
X1067239Y156126D01*
G01X1086655Y167088D02*
X1062548Y170872D01*
G01X1086673Y165769D02*
X1062657Y169538D01*
G01X1088068Y160412D02*
X1063084Y165409D01*
G01X1088068Y159086D02*
X1063149Y164070D01*
G01X1065539Y160526D02*
X1090539Y155526D01*
G01Y154200D02*
X1065621Y159183D01*
G01X1092239Y151126D02*
X1067239Y156126D01*
G01X1092239Y149800D02*
X1067306Y154786D01*
G01X1049893Y145148D02*
X1043344Y143171D01*
G01X1049893Y145148D02*
X1043344Y143171D01*
G01X1091491Y231870D02*
X1055656Y206778D01*
G01X1092425Y230936D02*
X1056166Y205547D01*
G01X1058381Y203359D02*
X1095570Y229399D01*
G01X1058891Y202128D02*
X1096504Y228465D01*
G01X1060030Y199671D02*
X1098060Y226300D01*
G01X1060540Y198440D02*
X1098994Y225366D01*
G01X1102152Y222098D02*
X1062658Y194444D01*
G01X1103086Y221164D02*
X1063168Y193213D01*
G01X1104898Y216505D02*
X1065303Y188780D01*
G01X1105832Y215571D02*
X1065813Y187549D01*
G01X1092425Y230936D02*
X1056166Y205547D01*
G01X1091491Y231870D02*
X1055656Y206778D01*
G01X1058891Y202128D02*
X1096504Y228465D01*
G01X1058381Y203359D02*
X1095570Y229399D01*
G01X1060540Y198440D02*
X1098994Y225366D01*
G01X1060030Y199671D02*
X1098060Y226300D01*
G01X1103086Y221164D02*
X1063168Y193213D01*
G01X1102152Y222098D02*
X1062658Y194444D01*
G01X1105832Y215571D02*
X1065813Y187549D01*
G01X1104898Y216505D02*
X1065303Y188780D01*
G01X1108782Y214403D02*
X1067053Y185184D01*
G01X1109716Y213469D02*
X1067563Y183953D01*
G01X1110928Y212180D02*
X1070271Y181814D01*
G01X1111782Y211194D02*
X1070801Y180587D01*
G01X1070718Y177994D02*
X1110001Y205500D01*
G01X1071228Y176763D02*
X1110934Y204566D01*
G01X1109716Y213469D02*
X1067563Y183953D01*
G01X1108782Y214403D02*
X1067053Y185184D01*
G01X1111782Y211194D02*
X1070801Y180587D01*
G01X1110928Y212180D02*
X1070271Y181814D01*
G01X1071228Y176763D02*
X1110934Y204566D01*
G01X1070718Y177994D02*
X1110001Y205500D01*
G01X1075382Y246954D02*
X1042746Y224102D01*
G01X1076316Y246020D02*
X1043256Y222871D01*
G01X1079377Y241820D02*
X1047500Y219500D01*
G01X1048010Y218269D02*
X1080311Y240886D01*
G01X1084298Y239603D02*
X1049490Y215231D01*
G01X1085232Y238669D02*
X1050000Y214000D01*
G01X1076316Y246020D02*
X1043256Y222871D01*
G01X1075382Y246954D02*
X1042746Y224102D01*
G01X1048010Y218269D02*
X1080311Y240886D01*
G01X1079377Y241820D02*
X1047500Y219500D01*
G01X1085232Y238669D02*
X1050000Y214000D01*
G01X1084298Y239603D02*
X1049490Y215231D01*
G01X1051990Y211231D02*
X1087972Y236426D01*
G01X1052500Y210000D02*
X1088906Y235492D01*
G01X1052500Y210000D02*
X1088906Y235492D01*
G01X1051990Y211231D02*
X1087972Y236426D01*
G01X1049898Y260559D02*
X1068769Y287510D01*
G01X1050832Y259625D02*
X1070000Y287000D01*
G01X1057500Y256500D02*
X1079115Y287369D01*
G01X1080346Y286859D02*
X1058434Y255566D01*
G01X1062500Y251000D02*
X1084467Y282372D01*
G01X1085698Y281862D02*
X1063434Y250066D01*
G01X1068390Y247159D02*
X1094453Y284382D01*
G01X1069324Y246225D02*
X1095684Y283872D01*
G01X1101122Y283714D02*
X1075382Y246954D01*
G01X1050832Y259625D02*
X1070000Y287000D01*
G01X1049898Y260559D02*
X1068769Y287510D01*
G01X1080346Y286859D02*
X1058434Y255566D01*
G01X1057500Y256500D02*
X1079115Y287369D01*
G01X1085698Y281862D02*
X1063434Y250066D01*
G01X1062500Y251000D02*
X1084467Y282372D01*
G01X1069324Y246225D02*
X1095684Y283872D01*
G01X1068390Y247159D02*
X1094453Y284382D01*
G01X1101122Y283714D02*
X1075382Y246954D01*
G01X1068769Y287510D02*
X1140134Y692249D01*
G01X1070000Y287000D02*
X1141455Y692249D01*
G01X1070000Y287000D02*
X1141455Y692249D01*
G01X1068769Y287510D02*
X1140134Y692249D01*
G01X1129241Y681956D02*
X1072165Y358233D01*
G01X1073396Y357723D02*
X1130562Y681956D01*
G01X1122851Y671406D02*
X1067500Y357500D01*
G01X1121530Y671406D02*
X1066269Y358010D01*
G01X1073396Y357723D02*
X1130562Y681956D01*
G01X1129241D02*
X1072165Y358233D01*
G01X1121530Y671406D02*
X1066269Y358010D01*
G01X1122851Y671406D02*
X1067500Y357500D01*
G01X1061269Y359510D02*
X1106732Y617271D01*
G01X1108053D02*
X1062500Y359000D01*
G01X1102100Y612946D02*
X1057500Y360000D01*
G01X1100779Y612946D02*
X1056269Y360510D01*
G01X1108053Y617271D02*
X1062500Y359000D01*
G01X1061269Y359510D02*
X1106732Y617271D01*
G01X1100779Y612946D02*
X1056269Y360510D01*
G01X1102100Y612946D02*
X1057500Y360000D01*
G01X1077321Y600690D02*
X1043382Y793159D01*
G01X1077321Y600690D02*
X1043382Y793159D01*
G01X1044703D02*
X1078642Y600690D01*
G01X1044703Y793159D02*
X1078642Y600690D01*
G01X1070595Y791616D02*
X1102100Y612946D01*
G01X1069274Y791616D02*
X1100779Y612946D01*
G01X1069274Y791616D02*
X1100779Y612946D01*
G01X1070595Y791616D02*
X1102100Y612946D01*
G01X1043382Y793159D02*
X1048400Y821614D01*
G01X1049700Y821500D02*
X1044703Y793159D01*
G01X1049700Y821500D02*
X1044703Y793159D01*
G01X1043382D02*
X1048400Y821614D01*
G01X1075600Y820000D02*
X1070595Y791616D01*
G01X1074279Y820000D02*
X1069274Y791616D01*
G01X1074279Y820000D02*
X1069274Y791616D01*
G01X1075600Y820000D02*
X1070595Y791616D01*
G01X1048400Y841486D02*
X1046219Y853854D01*
G01X1047540D02*
X1049700Y841600D01*
G01X1048400Y821614D02*
Y841486D01*
G01X1049700Y841600D02*
Y821500D01*
G01Y841600D02*
Y821500D01*
G01X1048400Y821614D02*
Y841486D01*
G01X1047540Y853854D02*
X1049700Y841600D01*
G01X1048400Y841486D02*
X1046219Y853854D01*
G01X1074956Y823651D02*
X1075600Y820000D01*
G01X1073656Y823537D02*
X1074279Y820000D01*
G01X1074956Y840944D02*
Y823651D01*
G01X1073656Y840830D02*
Y823537D01*
G01X1073909Y846884D02*
X1074956Y840944D01*
G01X1072588Y846884D02*
X1073656Y840830D01*
G01X1076128Y859470D02*
X1073909Y846884D01*
G01X1074807Y859470D02*
X1072588Y846884D01*
G01X1073656Y823537D02*
X1074279Y820000D01*
G01X1074956Y823651D02*
X1075600Y820000D01*
G01X1073656Y840830D02*
Y823537D01*
G01X1074956Y840944D02*
Y823651D01*
G01X1072588Y846884D02*
X1073656Y840830D01*
G01X1073909Y846884D02*
X1074956Y840944D01*
G01X1074807Y859470D02*
X1072588Y846884D01*
G01X1076128Y859470D02*
X1073909Y846884D01*
G01X1048563Y867147D02*
Y873200D01*
G01X1049863D02*
Y867032D01*
G01X1046219Y853854D02*
X1048563Y867147D01*
G01X1049863Y867032D02*
X1047540Y853854D01*
G01X1049863Y867032D02*
X1047540Y853854D01*
G01X1046219D02*
X1048563Y867147D01*
G01X1049863Y873200D02*
Y867032D01*
G01X1048563Y867147D02*
Y873200D01*
G01X1075060Y865527D02*
X1076128Y859470D01*
G01X1073760Y865410D02*
X1074807Y859470D01*
G01X1075060Y873700D02*
Y865527D01*
G01X1073760Y873200D02*
Y865410D01*
G01D02*
X1074807Y859470D01*
G01X1075060Y865527D02*
X1076128Y859470D01*
G01X1073760Y873200D02*
Y865410D01*
G01X1075060Y873700D02*
Y865527D01*
G01X1098858Y38429D02*
X1095917Y42631D01*
G01X1097924Y37496D02*
X1094686Y42121D01*
G01X1101602Y36508D02*
X1098858Y38429D01*
G01X1101092Y35277D02*
X1097924Y37496D01*
G01X1106215Y35695D02*
X1101602Y36508D01*
G01X1106215Y34374D02*
X1101092Y35277D01*
G01X1110052Y36371D02*
X1106215Y35695D01*
G01X1110562Y35140D02*
X1106215Y34374D01*
G01X1087559Y33472D02*
X1080424Y32213D01*
G01X1087559Y34793D02*
X1080733Y33588D01*
G01X1095900Y32001D02*
X1087559Y33472D01*
G01X1096409Y33232D02*
X1087559Y34793D01*
G01X1096999Y32820D02*
X1096409Y33232D01*
G01X1096607Y31507D02*
X1095900Y32001D01*
G01X1096999Y32820D02*
X1096409Y33232D01*
G01X1097353Y32572D02*
X1096999Y32820D01*
G01X1102548Y28933D02*
X1097353Y32572D01*
G01X1098070Y30482D02*
X1096607Y31507D01*
G01X1097353Y32572D02*
X1096999Y32820D01*
G01X1102548Y28933D02*
X1097353Y32572D01*
G01X1101802Y27868D02*
X1098070Y30482D01*
G01X1102548Y28933D02*
X1097353Y32572D01*
G01X1101801Y27868D02*
X1101802D01*
G01X1102548Y28933D02*
X1097353Y32572D01*
G01X1136830Y22889D02*
X1102548Y28933D01*
G01X1102038Y27702D02*
X1101801Y27868D01*
G01X1102548Y28933D02*
X1097353Y32572D01*
G01X1136830Y22889D02*
X1102548Y28933D01*
G01X1136830Y21568D02*
X1102038Y27702D01*
G01X1136830Y22889D02*
X1102548Y28933D01*
G01X1097924Y37496D02*
X1094686Y42121D01*
G01X1098858Y38429D02*
X1095917Y42631D01*
G01X1101092Y35277D02*
X1097924Y37496D01*
G01X1101602Y36508D02*
X1098858Y38429D01*
G01X1106215Y34374D02*
X1101092Y35277D01*
G01X1106215Y35695D02*
X1101602Y36508D01*
G01X1110562Y35140D02*
X1106215Y34374D01*
G01X1110052Y36371D02*
X1106215Y35695D01*
G01X1087559Y34793D02*
X1080733Y33588D01*
G01X1087559Y33472D02*
X1080424Y32213D01*
G01X1096409Y33232D02*
X1087559Y34793D01*
G01X1095900Y32001D02*
X1087559Y33472D01*
G01X1096999Y32820D02*
X1096409Y33232D01*
G01X1095900Y32001D02*
X1087559Y33472D01*
G01X1096607Y31507D02*
X1095900Y32001D01*
G01X1097353Y32572D02*
X1096999Y32820D01*
G01X1096607Y31507D02*
X1095900Y32001D01*
G01X1098070Y30482D02*
X1096607Y31507D01*
G01X1102548Y28933D02*
X1097353Y32572D01*
G01X1096607Y31507D02*
X1095900Y32001D01*
G01X1098070Y30482D02*
X1096607Y31507D01*
G01X1101802Y27868D02*
X1098070Y30482D01*
G01X1101801Y27868D02*
X1101802D01*
G01X1102038Y27702D02*
X1101801Y27868D01*
G01X1136830Y22889D02*
X1102548Y28933D01*
G01X1101801Y27868D02*
X1101802D01*
G01X1102038Y27702D02*
X1101801Y27868D01*
G01X1136830Y21568D02*
X1102038Y27702D01*
G01X1098581Y71447D02*
X1077579Y75150D01*
G01X1098695Y72747D02*
X1077564Y76473D01*
G01X1101230Y71447D02*
X1098581D01*
G01X1101230Y72747D02*
X1098695D01*
G01X1101553Y71444D02*
X1101230D01*
G01Y72747D02*
X1098695D01*
G01X1100090Y62869D02*
X1093331Y67602D01*
G01X1100600Y64100D02*
X1093841Y68833D01*
G01X1105605Y61896D02*
X1100090Y62869D01*
G01X1105831Y63177D02*
X1100600Y64100D01*
G01X1105604Y61896D02*
X1105605D01*
G01X1105831Y63177D02*
X1100600Y64100D01*
G01X1110904Y64071D02*
X1105831Y63177D01*
G01Y61856D02*
X1105604Y61896D01*
G01X1105831Y63177D02*
X1100600Y64100D01*
G01X1110904Y64071D02*
X1105831Y63177D01*
G01X1111414Y62840D02*
X1105831Y61856D01*
G01X1110904Y64071D02*
X1105831Y63177D01*
G01X1081527Y67063D02*
X1076256Y67993D01*
G01X1081017Y65832D02*
X1076271Y66670D01*
G01X1089880Y61214D02*
X1081527Y67063D01*
G01X1088946Y60280D02*
X1081017Y65832D01*
G01X1093569Y55947D02*
X1089880Y61214D01*
G01X1092338Y55437D02*
X1088946Y60280D01*
G01X1095917Y42631D02*
X1093569Y55947D01*
G01X1094636Y42406D02*
X1092338Y55437D01*
G01X1094686Y42121D02*
X1094635Y42406D01*
G01X1098695Y72747D02*
X1077564Y76473D01*
G01X1098581Y71447D02*
X1077579Y75150D01*
G01X1101230Y72747D02*
X1098695D01*
G01X1101230Y71447D02*
X1098581D01*
G01X1101553Y71444D02*
X1101230D01*
G01X1100600Y64100D02*
X1093841Y68833D01*
G01X1100090Y62869D02*
X1093331Y67602D01*
G01X1105831Y63177D02*
X1100600Y64100D01*
G01X1105605Y61896D02*
X1100090Y62869D01*
G01X1105604Y61896D02*
X1105605D01*
G01X1105831Y61856D02*
X1105604Y61896D01*
G01X1110904Y64071D02*
X1105831Y63177D01*
G01X1105604Y61896D02*
X1105605D01*
G01X1105831Y61856D02*
X1105604Y61896D01*
G01X1111414Y62840D02*
X1105831Y61856D01*
G01X1081017Y65832D02*
X1076271Y66670D01*
G01X1081527Y67063D02*
X1076256Y67993D01*
G01X1088946Y60280D02*
X1081017Y65832D01*
G01X1089880Y61214D02*
X1081527Y67063D01*
G01X1092338Y55437D02*
X1088946Y60280D01*
G01X1093569Y55947D02*
X1089880Y61214D01*
G01X1094636Y42406D02*
X1092338Y55437D01*
G01X1095917Y42631D02*
X1093569Y55947D01*
G01X1094686Y42121D02*
X1094635Y42406D01*
G01X1095917Y42631D02*
X1093569Y55947D01*
G01X1093129Y95856D02*
X1079667Y98231D01*
G01X1093129Y97177D02*
X1079653Y99554D01*
G01X1118731Y100371D02*
X1093129Y95856D01*
G01X1118388Y101631D02*
X1093129Y97177D01*
G01X1090295Y86030D02*
X1078546Y88101D01*
G01X1090295Y84709D02*
X1078546Y86780D01*
G01X1119697Y91214D02*
X1090295Y86030D01*
G01X1119697Y89893D02*
X1090295Y84709D01*
G01X1093129Y97177D02*
X1079653Y99554D01*
G01X1093129Y95856D02*
X1079667Y98231D01*
G01X1118388Y101631D02*
X1093129Y97177D01*
G01X1118731Y100371D02*
X1093129Y95856D01*
G01X1090295Y84709D02*
X1078546Y86780D01*
G01X1090295Y86030D02*
X1078546Y88101D01*
G01X1119697Y89893D02*
X1090295Y84709D01*
G01X1119697Y91214D02*
X1090295Y86030D01*
G01X1106638Y84723D02*
X1111596D01*
G01X1111096Y83423D02*
X1106947D01*
G01X1099707Y81242D02*
X1106638Y84723D01*
G01X1106947Y83423D02*
X1100121Y79994D01*
G01X1090984Y79704D02*
X1099707Y81242D01*
G01X1091209Y78422D02*
X1090984Y78383D01*
G01X1095571Y79192D02*
X1091209Y78423D01*
G01X1100121Y79994D02*
X1095571Y79192D01*
G01X1091209Y78422D02*
X1090984Y78383D01*
G01X1091209Y78422D02*
X1090984Y78383D01*
G01Y79704D02*
X1099707Y81242D01*
G01X1095571Y79192D02*
X1091209Y78423D01*
G01X1090984Y79704D02*
X1099707Y81242D01*
G01X1100121Y79994D02*
X1095571Y79192D01*
G01X1090984Y79704D02*
X1099707Y81242D01*
G01X1106947Y83423D02*
X1100121Y79994D01*
G01X1099707Y81242D02*
X1106638Y84723D01*
G01X1111096Y83423D02*
X1106947D01*
G01X1106638Y84723D02*
X1111596D01*
G01X1112665Y126482D02*
X1100446Y135037D01*
G01X1106030Y129540D02*
X1099923Y133815D01*
G01X1112138Y125263D02*
X1106030Y129540D01*
G01X1102985Y118949D02*
X1119559Y116028D01*
G01Y117349D02*
X1103495Y120180D01*
G01X1100648Y120586D02*
X1102985Y118949D01*
G01X1102444Y120916D02*
X1097892Y124103D01*
G01X1103495Y120180D02*
X1102444Y120916D01*
G01X1100552Y120653D02*
X1100648Y120586D01*
G01X1102444Y120916D02*
X1097892Y124103D01*
G01X1099014Y121730D02*
X1100552Y120653D01*
G01X1102444Y120916D02*
X1097892Y124103D01*
G01X1097382Y122872D02*
X1099014Y121730D01*
G01X1102444Y120916D02*
X1097892Y124103D01*
G01X1099569Y115899D02*
X1083122Y118504D01*
G01X1091549Y118486D02*
X1099773Y117184D01*
G01X1083326Y119789D02*
X1091549Y118486D01*
G01X1120226Y112625D02*
X1099569Y115899D01*
G01X1099773Y117184D02*
X1120199Y113946D01*
G01X1106030Y129540D02*
X1099923Y133815D01*
G01X1112665Y126482D02*
X1100446Y135037D01*
G01X1112138Y125263D02*
X1106030Y129540D01*
G01X1112665Y126482D02*
X1100446Y135037D01*
G01X1106038Y123473D02*
X1094805Y130397D01*
G01X1106573Y124671D02*
X1095276Y131635D01*
G01X1119800Y119400D02*
X1106038Y123473D01*
G01X1119877Y120733D02*
X1106573Y124671D01*
G01X1102444Y120916D02*
X1097892Y124103D01*
G01X1100648Y120586D02*
X1102985Y118949D01*
G01X1100552Y120653D02*
X1100648Y120586D01*
G01X1099014Y121730D02*
X1100552Y120653D01*
G01X1097382Y122872D02*
X1099014Y121730D01*
G01X1103495Y120180D02*
X1102444Y120916D01*
G01X1100648Y120586D02*
X1102985Y118949D01*
G01X1119559Y117349D02*
X1103495Y120180D01*
G01X1102985Y118949D02*
X1119559Y116028D01*
G01X1099773Y117184D02*
X1120199Y113946D01*
G01X1120226Y112625D02*
X1099569Y115899D01*
G01X1091549Y118486D02*
X1099773Y117184D01*
G01X1099569Y115899D02*
X1083122Y118504D01*
G01X1083326Y119789D02*
X1091549Y118486D01*
G01X1099569Y115899D02*
X1083122Y118504D01*
G01X1106573Y124671D02*
X1095276Y131635D01*
G01X1106038Y123473D02*
X1094805Y130397D01*
G01X1119877Y120733D02*
X1106573Y124671D01*
G01X1119800Y119400D02*
X1106038Y123473D01*
G01X1098121Y167889D02*
X1086673Y165769D01*
G01X1109116Y171249D02*
X1086655Y167088D01*
G01X1109353Y169970D02*
X1098121Y167889D01*
G01X1109116Y171249D02*
X1086655Y167088D01*
G01X1112858Y170620D02*
X1109353Y169970D01*
G01X1112912Y171953D02*
X1109116Y171249D01*
G01X1113139Y164100D02*
X1088068Y159086D01*
G01X1113139Y165426D02*
X1088068Y160412D01*
G01X1115539Y159200D02*
X1090539Y154200D01*
G01Y155526D02*
X1115539Y160526D01*
G01X1117239Y154800D02*
X1092239Y149800D01*
G01X1117239Y156126D02*
X1092239Y151126D01*
G01X1109116Y171249D02*
X1086655Y167088D01*
G01X1098121Y167889D02*
X1086673Y165769D01*
G01X1109353Y169970D02*
X1098121Y167889D01*
G01X1112912Y171953D02*
X1109116Y171249D01*
G01X1112858Y170620D02*
X1109353Y169970D01*
G01X1113139Y165426D02*
X1088068Y160412D01*
G01X1113139Y164100D02*
X1088068Y159086D01*
G01X1090539Y155526D02*
X1115539Y160526D01*
G01Y159200D02*
X1090539Y154200D01*
G01X1117239Y156126D02*
X1092239Y151126D01*
G01X1117239Y154800D02*
X1092239Y149800D01*
G01X1107743Y282330D02*
X1079377Y241820D01*
G01X1080311Y240886D02*
X1108974Y281820D01*
G01X1110828Y277493D02*
X1084298Y239603D01*
G01X1112059Y276983D02*
X1085232Y238669D01*
G01X1080311Y240886D02*
X1108974Y281820D01*
G01X1107743Y282330D02*
X1079377Y241820D01*
G01X1112059Y276983D02*
X1085232Y238669D01*
G01X1110828Y277493D02*
X1084298Y239603D01*
G01X1087972Y236426D02*
X1116166Y276692D01*
G01X1088906Y235492D02*
X1117397Y276182D01*
G01X1122897Y276722D02*
X1091491Y231870D01*
G01X1124128Y276212D02*
X1092425Y230936D01*
G01X1095570Y229399D02*
X1127500Y275000D01*
G01X1096504Y228465D02*
X1128731Y274490D01*
G01X1098060Y226300D02*
X1130970Y273301D01*
G01X1098994Y225366D02*
X1132201Y272791D01*
G01X1136112Y270601D02*
X1102152Y222098D01*
G01X1137343Y270091D02*
X1103086Y221164D01*
G01X1139096Y265346D02*
X1104898Y216505D01*
G01X1140327Y264836D02*
X1105832Y215571D01*
G01X1088906Y235492D02*
X1117397Y276182D01*
G01X1087972Y236426D02*
X1116166Y276692D01*
G01X1124128Y276212D02*
X1092425Y230936D01*
G01X1122897Y276722D02*
X1091491Y231870D01*
G01X1096504Y228465D02*
X1128731Y274490D01*
G01X1095570Y229399D02*
X1127500Y275000D01*
G01X1098994Y225366D02*
X1132201Y272791D01*
G01X1098060Y226300D02*
X1130970Y273301D01*
G01X1137343Y270091D02*
X1103086Y221164D01*
G01X1136112Y270601D02*
X1102152Y222098D01*
G01X1140327Y264836D02*
X1105832Y215571D01*
G01X1139096Y265346D02*
X1104898Y216505D01*
G01X1141991Y261832D02*
X1108782Y214403D01*
G01X1143222Y261322D02*
X1109716Y213469D01*
G01X1143222Y261322D02*
X1109716Y213469D01*
G01X1141991Y261832D02*
X1108782Y214403D01*
G01X1102353Y283204D02*
X1076316Y246020D01*
G01X1102353Y283204D02*
X1076316Y246020D01*
G01X1079115Y287369D02*
X1151610Y698512D01*
G01X1152931D02*
X1080346Y286859D01*
G01X1084467Y282372D02*
X1161771Y720780D01*
G01X1163092D02*
X1085698Y281862D01*
G01X1094453Y284382D02*
X1174026Y735665D01*
G01X1095684Y283872D02*
X1175347Y735665D01*
G01X1187388Y772956D02*
X1101122Y283714D01*
G01X1188709Y772956D02*
X1102353Y283204D01*
G01X1200658Y809279D02*
X1107743Y282330D01*
G01X1108974Y281820D02*
X1201979Y809279D01*
G01X1152931Y698512D02*
X1080346Y286859D01*
G01X1079115Y287369D02*
X1151610Y698512D01*
G01X1163092Y720780D02*
X1085698Y281862D01*
G01X1084467Y282372D02*
X1161771Y720780D01*
G01X1095684Y283872D02*
X1175347Y735665D01*
G01X1094453Y284382D02*
X1174026Y735665D01*
G01X1188709Y772956D02*
X1102353Y283204D01*
G01X1187388Y772956D02*
X1101122Y283714D01*
G01X1108974Y281820D02*
X1201979Y809279D01*
G01X1200658D02*
X1107743Y282330D01*
G01X1106732Y617271D02*
X1078890Y775165D01*
G01X1080211D02*
X1108053Y617271D01*
G01X1080211Y775165D02*
X1108053Y617271D01*
G01X1106732D02*
X1078890Y775165D01*
G01X1097664Y814250D02*
X1122851Y671406D01*
G01X1108975Y742603D02*
X1121530Y671406D01*
G01X1096343Y814250D02*
X1108975Y742603D01*
G01D02*
X1121530Y671406D01*
G01X1097664Y814250D02*
X1122851Y671406D01*
G01X1096343Y814250D02*
X1108975Y742603D01*
G01X1097664Y814250D02*
X1122851Y671406D01*
G01X1078890Y775165D02*
X1086200Y816615D01*
G01X1087500Y816501D02*
X1080211Y775165D01*
G01X1087500Y816501D02*
X1080211Y775165D01*
G01X1078890D02*
X1086200Y816615D01*
G01X1107731Y803946D02*
X1129241Y681956D01*
G01X1130562D02*
X1109052Y803946D01*
G01X1111373Y824595D02*
X1107731Y803946D01*
G01X1109052D02*
X1112673Y824481D01*
G01X1099896Y826906D02*
X1097664Y814250D01*
G01X1098596Y827020D02*
X1096343Y814250D01*
G01X1109052Y803946D02*
X1112673Y824481D01*
G01X1111373Y824595D02*
X1107731Y803946D01*
G01X1130562Y681956D02*
X1109052Y803946D01*
G01X1107731D02*
X1129241Y681956D01*
G01X1098596Y827020D02*
X1096343Y814250D01*
G01X1099896Y826906D02*
X1097664Y814250D01*
G01X1099896Y840916D02*
Y826906D01*
G01X1098596Y840802D02*
Y827020D01*
G01X1097780Y852916D02*
X1099896Y840916D01*
G01X1096459Y852916D02*
X1098596Y840802D01*
G01D02*
Y827020D01*
G01X1099896Y840916D02*
Y826906D01*
G01X1096459Y852916D02*
X1098596Y840802D01*
G01X1097780Y852916D02*
X1099896Y840916D01*
G01X1086200Y840986D02*
X1084404Y851169D01*
G01X1085725D02*
X1087500Y841100D01*
G01X1086200Y816615D02*
Y840986D01*
G01X1087500Y841100D02*
Y816501D01*
G01Y841100D02*
Y816501D01*
G01X1086200Y816615D02*
Y840986D01*
G01X1085725Y851169D02*
X1087500Y841100D01*
G01X1086200Y840986D02*
X1084404Y851169D01*
G01X1109420Y851884D02*
X1111373Y840813D01*
G01X1111555Y863989D02*
X1109420Y851884D01*
G01X1100257Y866957D02*
X1097780Y852916D01*
G01X1098957Y867071D02*
X1096459Y852916D01*
G01X1100257Y873200D02*
Y866957D01*
G01X1098957Y873200D02*
Y867071D01*
G01X1111555Y863989D02*
X1109420Y851884D01*
G01D02*
X1111373Y840813D01*
G01X1098957Y867071D02*
X1096459Y852916D01*
G01X1100257Y866957D02*
X1097780Y852916D01*
G01X1098957Y873200D02*
Y867071D01*
G01X1100257Y873200D02*
Y866957D01*
G01X1086358Y862251D02*
Y873200D01*
G01X1087658D02*
Y862133D01*
G01X1084404Y851169D02*
X1086358Y862251D01*
G01X1087658Y862133D02*
X1085725Y851169D01*
G01X1087658Y862133D02*
X1085725Y851169D01*
G01X1084404D02*
X1086358Y862251D01*
G01X1087658Y873200D02*
Y862133D01*
G01X1086358Y862251D02*
Y873200D01*
G01X1114320Y39359D02*
X1110052Y36371D01*
G01X1115254Y38425D02*
X1110562Y35140D01*
G01X1115149Y40544D02*
X1114320Y39359D01*
G01X1116380Y40034D02*
X1115254Y38425D01*
G01X1116901Y42989D02*
X1116380Y40034D01*
G01X1145910Y23169D02*
X1136830Y21568D01*
G01X1145400Y24400D02*
X1136830Y22889D01*
G01X1115254Y38425D02*
X1110562Y35140D01*
G01X1114320Y39359D02*
X1110052Y36371D01*
G01X1116380Y40034D02*
X1115254Y38425D01*
G01X1115149Y40544D02*
X1114320Y39359D01*
G01X1116901Y42989D02*
X1116380Y40034D01*
G01X1145400Y24400D02*
X1136830Y22889D01*
G01X1145910Y23169D02*
X1136830Y21568D01*
G01X1126723Y73560D02*
X1111414Y62840D01*
G01X1126213Y74791D02*
X1110904Y64071D01*
G01X1134884Y75000D02*
X1126723Y73560D01*
G01X1115580Y42989D02*
X1115149Y40544D01*
G01X1115309Y44526D02*
X1115580Y42989D01*
G01X1116540Y45036D02*
X1116901Y42989D01*
G01X1110648Y51182D02*
X1115309Y44526D01*
G01X1111879Y51693D02*
X1116540Y45036D01*
G01X1110225Y53580D02*
X1110648Y51182D01*
G01X1111546Y53580D02*
X1111879Y51693D01*
G01X1110506Y55176D02*
X1110225Y53580D01*
G01X1111737Y54666D02*
X1111546Y53580D01*
G01X1111303Y56312D02*
X1110506Y55176D01*
G01X1112236Y55378D02*
X1111737Y54666D01*
G01X1113393Y57776D02*
X1111303Y56312D01*
G01X1113903Y56545D02*
X1112236Y55378D01*
G01X1117500Y58500D02*
X1113393Y57776D01*
G01X1117500Y57179D02*
X1113903Y56545D01*
G01X1119534Y58141D02*
X1117500Y58500D01*
G01X1119534Y56820D02*
X1117500Y57179D01*
G01X1128743Y59766D02*
X1119534Y58141D01*
G01X1129373Y58556D02*
X1119534Y56820D01*
G01X1135933Y66955D02*
X1128743Y59766D01*
G01X1135465Y64647D02*
X1129373Y58556D01*
G01X1141865Y58330D02*
X1144697Y59499D01*
G01X1142464Y57169D02*
X1144955Y58199D01*
G01X1139490Y56872D02*
X1141844Y58316D01*
G01X1140265Y55821D02*
X1142463Y57170D01*
G01X1139018Y56458D02*
X1139490Y56872D01*
G01X1139994Y55584D02*
X1140265Y55821D01*
G01X1138130Y55570D02*
X1139018Y56458D01*
G01X1136162Y51762D02*
X1139753Y55353D01*
G01X1126213Y74791D02*
X1110904Y64071D01*
G01X1126723Y73560D02*
X1111414Y62840D01*
G01X1134884Y75000D02*
X1126723Y73560D01*
G01X1115580Y42989D02*
X1115149Y40544D01*
G01X1116540Y45036D02*
X1116901Y42989D01*
G01X1115309Y44526D02*
X1115580Y42989D01*
G01X1111879Y51693D02*
X1116540Y45036D01*
G01X1110648Y51182D02*
X1115309Y44526D01*
G01X1111546Y53580D02*
X1111879Y51693D01*
G01X1110225Y53580D02*
X1110648Y51182D01*
G01X1111737Y54666D02*
X1111546Y53580D01*
G01X1110506Y55176D02*
X1110225Y53580D01*
G01X1112236Y55378D02*
X1111737Y54666D01*
G01X1111303Y56312D02*
X1110506Y55176D01*
G01X1113903Y56545D02*
X1112236Y55378D01*
G01X1113393Y57776D02*
X1111303Y56312D01*
G01X1117500Y57179D02*
X1113903Y56545D01*
G01X1117500Y58500D02*
X1113393Y57776D01*
G01X1119534Y56820D02*
X1117500Y57179D01*
G01X1119534Y58141D02*
X1117500Y58500D01*
G01X1129373Y58556D02*
X1119534Y56820D01*
G01X1128743Y59766D02*
X1119534Y58141D01*
G01X1135465Y64647D02*
X1129373Y58556D01*
G01X1135933Y66955D02*
X1128743Y59766D01*
G01X1142464Y57169D02*
X1144955Y58199D01*
G01X1141865Y58330D02*
X1144697Y59499D01*
G01X1140265Y55821D02*
X1142463Y57170D01*
G01X1139490Y56872D02*
X1141844Y58316D01*
G01X1139994Y55584D02*
X1140265Y55821D01*
G01X1139018Y56458D02*
X1139490Y56872D01*
G01X1136162Y51762D02*
X1139753Y55353D01*
G01X1138130Y55570D02*
X1139018Y56458D01*
G01X1124432Y102500D02*
X1118731Y100371D01*
G01X1124197Y103800D02*
X1118388Y101631D01*
G01X1145165Y102500D02*
X1124432D01*
G01X1145279Y103800D02*
X1124197D01*
G01X1131000Y89221D02*
X1119697Y91214D01*
G01X1131000Y87900D02*
X1119697Y89893D01*
G01X1141320Y91041D02*
X1131000Y89221D01*
G01X1141320Y89720D02*
X1131000Y87900D01*
G01X1152453Y89078D02*
X1141320Y91041D01*
G01X1151943Y87847D02*
X1141320Y89720D01*
G01X1124197Y103800D02*
X1118388Y101631D01*
G01X1124432Y102500D02*
X1118731Y100371D01*
G01X1145279Y103800D02*
X1124197D01*
G01X1145165Y102500D02*
X1124432D01*
G01X1131000Y87900D02*
X1119697Y89893D01*
G01X1131000Y89221D02*
X1119697Y91214D01*
G01X1141320Y89720D02*
X1131000Y87900D01*
G01X1141320Y91041D02*
X1131000Y89221D01*
G01X1151943Y87847D02*
X1141320Y89720D01*
G01X1152453Y89078D02*
X1141320Y91041D01*
G01X1111596Y84723D02*
X1112254Y84130D01*
G01X1111384Y83164D02*
X1111096Y83423D01*
G01X1134770Y76300D02*
X1126213Y74791D01*
G01X1142627Y75000D02*
X1134884D01*
G01X1142627Y76300D02*
X1134770D01*
G01X1143637Y74683D02*
G03X1142627Y75000I-1012J-1455D01*
G01X1144379Y75752D02*
G03X1142627Y76300I-1752J-2525D01*
G01X1144379Y75752D02*
G03X1142627Y76300I-1752J-2525D01*
G01X1111384Y83164D02*
X1111096Y83423D01*
G01X1111596Y84723D02*
X1112254Y84130D01*
G01X1134770Y76300D02*
X1126213Y74791D01*
G01X1142627Y76300D02*
X1134770D01*
G01X1142627Y75000D02*
X1134884D01*
G01X1144379Y75752D02*
G03X1142627Y76300I-1752J-2525D01*
G01X1143637Y74683D02*
G03X1142627Y75000I-1012J-1455D01*
G01X1122435Y124447D02*
X1112665Y126482D01*
G01X1122415Y123123D02*
X1112138Y125263D01*
G01X1130578Y125885D02*
X1122435Y124447D01*
G01X1130578Y124564D02*
X1122415Y123123D01*
G01X1138324Y124520D02*
X1130578Y125885D01*
G01X1138323Y123200D02*
X1130578Y124564D01*
G01X1147539Y126125D02*
X1138324Y124520D01*
G01X1139179Y123349D02*
X1138323Y123200D01*
G01X1141075Y123679D02*
X1139179Y123349D01*
G01X1141879Y123819D02*
X1141075Y123679D01*
G01X1142002Y123841D02*
X1141879Y123819D01*
G01X1145458Y124442D02*
X1142002Y123841D01*
G01X1139834Y116729D02*
X1157620Y119863D01*
G01Y121184D02*
X1139830Y118049D01*
G01X1131547Y118143D02*
X1139834Y116729D01*
G01X1139830Y118049D02*
X1131543Y119463D01*
G01X1119559Y116028D02*
X1131547Y118143D01*
G01X1131543Y119463D02*
X1119559Y117349D01*
G01X1131755Y114931D02*
X1120226Y112625D01*
G01X1120199Y113946D02*
X1131729Y116252D01*
G01X1141441Y113382D02*
X1131755Y114931D01*
G01X1131729Y116252D02*
X1141415Y114703D01*
G01X1153450Y115784D02*
X1141441Y113382D01*
G01X1141415Y114703D02*
X1153450Y117110D01*
G01X1122415Y123123D02*
X1112138Y125263D01*
G01X1122435Y124447D02*
X1112665Y126482D01*
G01X1130578Y124564D02*
X1122415Y123123D01*
G01X1130578Y125885D02*
X1122435Y124447D01*
G01X1138323Y123200D02*
X1130578Y124564D01*
G01X1138324Y124520D02*
X1130578Y125885D01*
G01X1139179Y123349D02*
X1138323Y123200D01*
G01X1147539Y126125D02*
X1138324Y124520D01*
G01X1141075Y123679D02*
X1139179Y123349D01*
G01X1147539Y126125D02*
X1138324Y124520D01*
G01X1141879Y123819D02*
X1141075Y123679D01*
G01X1147539Y126125D02*
X1138324Y124520D01*
G01X1142002Y123841D02*
X1141879Y123819D01*
G01X1147539Y126125D02*
X1138324Y124520D01*
G01X1145458Y124442D02*
X1142002Y123841D01*
G01X1147539Y126125D02*
X1138324Y124520D01*
G01X1147539Y126125D02*
X1138324Y124520D01*
G01X1131216Y121352D02*
X1119800Y119400D01*
G01X1131205Y122669D02*
X1119879Y120733D01*
G01X1131441Y122633D02*
X1131205Y122669D01*
G01X1131229Y121350D02*
X1131216Y121352D01*
G01X1131205Y122669D02*
X1119879Y120733D01*
G01X1139149Y121276D02*
X1131441Y122633D01*
G01X1139150Y119955D02*
X1131229Y121350D01*
G01X1131441Y122633D02*
X1131205Y122669D01*
G01X1139149Y121276D02*
X1131441Y122633D01*
G01X1157917Y123263D02*
X1139150Y119955D01*
G01X1157917Y124584D02*
X1139149Y121276D01*
G01X1131543Y119463D02*
X1119559Y117349D01*
G01Y116028D02*
X1131547Y118143D01*
G01X1139830Y118049D02*
X1131543Y119463D01*
G01X1131547Y118143D02*
X1139834Y116729D01*
G01X1157620Y121184D02*
X1139830Y118049D01*
G01X1139834Y116729D02*
X1157620Y119863D01*
G01X1141415Y114703D02*
X1153450Y117110D01*
G01Y115784D02*
X1141441Y113382D01*
G01X1131729Y116252D02*
X1141415Y114703D01*
G01X1141441Y113382D02*
X1131755Y114931D01*
G01X1120199Y113946D02*
X1131729Y116252D01*
G01X1131755Y114931D02*
X1120226Y112625D01*
G01X1131205Y122669D02*
X1119879Y120733D01*
G01X1131216Y121352D02*
X1119800Y119400D01*
G01X1131229Y121350D02*
X1131216Y121352D01*
G01X1131441Y122633D02*
X1131205Y122669D01*
G01X1131216Y121352D02*
X1119800Y119400D01*
G01X1139150Y119955D02*
X1131229Y121350D01*
G01X1139149Y121276D02*
X1131441Y122633D01*
G01X1131229Y121350D02*
X1131216Y121352D01*
G01X1139150Y119955D02*
X1131229Y121350D01*
G01X1157917Y124584D02*
X1139149Y121276D01*
G01X1157917Y123263D02*
X1139150Y119955D01*
G01X1141005Y109319D02*
X1132672Y110788D01*
G01X1141230Y110600D02*
X1132672Y112109D01*
G01X1141215Y109277D02*
X1141005Y109319D01*
G01X1141230Y110600D02*
X1132672Y112109D01*
G01X1152263Y112545D02*
X1141230Y110600D01*
G01X1152263Y111224D02*
X1141215Y109277D01*
G01X1152263Y112545D02*
X1141230Y110600D01*
G01D02*
X1132672Y112109D01*
G01X1141005Y109319D02*
X1132672Y110788D01*
G01X1141215Y109277D02*
X1141005Y109319D01*
G01X1152263Y112545D02*
X1141230Y110600D01*
G01X1141215Y109277D02*
X1141005Y109319D01*
G01X1152263Y111224D02*
X1141215Y109277D01*
G01X1133104Y165130D02*
X1112858Y170620D01*
G01X1133160Y166462D02*
X1112912Y171953D01*
G01X1183207Y174751D02*
X1133111Y165131D01*
G01X1158060Y171246D02*
X1133159Y166465D01*
G01X1131475Y160433D02*
X1113139Y164100D01*
G01X1131490Y161756D02*
X1113139Y165426D01*
G01X1178867Y168790D02*
X1131475Y160433D01*
G01X1155177Y165933D02*
X1131490Y161756D01*
G01X1131821Y155943D02*
X1115539Y159200D01*
G01Y160526D02*
X1131818Y157270D01*
G01X1172708Y164310D02*
X1131821Y155943D01*
G01X1131818Y157270D02*
X1172713Y165638D01*
G01X1132148Y151817D02*
X1117239Y154800D01*
G01X1132145Y153144D02*
X1117239Y156126D01*
G01X1153037Y156080D02*
X1132148Y151817D01*
G01X1173933Y161674D02*
X1132145Y153144D01*
G01X1173933Y161674D02*
X1132145Y153144D01*
G01X1173933Y161674D02*
X1132145Y153144D01*
G01X1133160Y166462D02*
X1112912Y171953D01*
G01X1133104Y165130D02*
X1112858Y170620D01*
G01X1158060Y171246D02*
X1133159Y166465D01*
G01X1183207Y174751D02*
X1133111Y165131D01*
G01X1183207Y174751D02*
X1133111Y165131D01*
G01X1131490Y161756D02*
X1113139Y165426D01*
G01X1131475Y160433D02*
X1113139Y164100D01*
G01X1155177Y165933D02*
X1131490Y161756D01*
G01X1178867Y168790D02*
X1131475Y160433D01*
G01X1178867Y168790D02*
X1131475Y160433D01*
G01X1131818Y157270D02*
X1172713Y165638D01*
G01X1172708Y164310D02*
X1131821Y155943D01*
G01X1115539Y160526D02*
X1131818Y157270D01*
G01X1131821Y155943D02*
X1115539Y159200D01*
G01X1132145Y153144D02*
X1117239Y156126D01*
G01X1132148Y151817D02*
X1117239Y154800D01*
G01X1173933Y161674D02*
X1132145Y153144D01*
G01X1153037Y156080D02*
X1132148Y151817D01*
G01X1110001Y205500D02*
X1148460Y260248D01*
G01X1110934Y204566D02*
X1149685Y259730D01*
G01X1110934Y204566D02*
X1149685Y259730D01*
G01X1110001Y205500D02*
X1148460Y260248D01*
G01X1111003Y212255D02*
X1110928Y212180D01*
G01X1112003Y211416D02*
X1111782Y211194D01*
G01X1145626Y261700D02*
X1111003Y212255D01*
G01X1146856Y261190D02*
X1112003Y211416D01*
G01D02*
X1111782Y211194D01*
G01X1111003Y212255D02*
X1110928Y212180D01*
G01X1146856Y261190D02*
X1112003Y211416D01*
G01X1145626Y261700D02*
X1111003Y212255D01*
G01X1117397Y276182D02*
X1214023Y824169D01*
G01X1211870Y773826D02*
X1124128Y276212D01*
G01X1127500Y275000D02*
X1211813Y753161D01*
G01X1128731Y274490D02*
X1213044Y752651D01*
G01X1130970Y273301D02*
X1213689Y742418D01*
G01X1132201Y272791D02*
X1214920Y741908D01*
G01X1218184Y736056D02*
X1136112Y270601D01*
G01X1219415Y735546D02*
X1137343Y270091D01*
G01X1218700Y716801D02*
X1139096Y265346D01*
G01X1219931Y716291D02*
X1140327Y264836D01*
G01X1117397Y276182D02*
X1214023Y824169D01*
G01X1211870Y773826D02*
X1124128Y276212D01*
G01X1128731Y274490D02*
X1213044Y752651D01*
G01X1127500Y275000D02*
X1211813Y753161D01*
G01X1132201Y272791D02*
X1214920Y741908D01*
G01X1130970Y273301D02*
X1213689Y742418D01*
G01X1219415Y735546D02*
X1137343Y270091D01*
G01X1218184Y736056D02*
X1136112Y270601D01*
G01X1219931Y716291D02*
X1140327Y264836D01*
G01X1218700Y716801D02*
X1139096Y265346D01*
G01X1221452Y712289D02*
X1141991Y261832D01*
G01X1222683Y711779D02*
X1143222Y261322D01*
G01X1222683Y711779D02*
X1143222Y261322D01*
G01X1221452Y712289D02*
X1141991Y261832D01*
G01X1211126Y846314D02*
X1110828Y277493D01*
G01X1212357Y845804D02*
X1112059Y276983D01*
G01X1212357Y845804D02*
X1112059Y276983D01*
G01X1211126Y846314D02*
X1110828Y277493D01*
G01X1116166Y276692D02*
X1212702Y824169D01*
G01X1210639Y774336D02*
X1122897Y276722D01*
G01X1116166Y276692D02*
X1212702Y824169D01*
G01X1210639Y774336D02*
X1122897Y276722D01*
G01X1140134Y692249D02*
X1123200Y788281D01*
G01X1141455Y692249D02*
X1124521Y788281D01*
G01X1141455Y692249D02*
X1124521Y788281D01*
G01X1140134Y692249D02*
X1123200Y788281D01*
G01X1151610Y698512D02*
X1134197Y797268D01*
G01X1151610Y698512D02*
X1134197Y797268D01*
G01X1135518D02*
X1152931Y698512D01*
G01X1135518Y797268D02*
X1152931Y698512D01*
G01X1127043Y810098D02*
X1124100Y826797D01*
G01X1128364Y810098D02*
X1125400Y826911D01*
G01X1123200Y788281D02*
X1127043Y810098D01*
G01X1124521Y788281D02*
X1128364Y810098D01*
G01X1134197Y797268D02*
X1137845Y817957D01*
G01X1139166D02*
X1135518Y797268D01*
G01X1128364Y810098D02*
X1125400Y826911D01*
G01X1127043Y810098D02*
X1124100Y826797D01*
G01X1124521Y788281D02*
X1128364Y810098D01*
G01X1123200Y788281D02*
X1127043Y810098D01*
G01X1139166Y817957D02*
X1135518Y797268D01*
G01X1134197D02*
X1137845Y817957D01*
G01X1111373Y840813D02*
Y824595D01*
G01X1112673Y824481D02*
Y840927D01*
G01D02*
X1110741Y851884D01*
G01X1112673Y840927D02*
X1110741Y851884D01*
G01X1112673Y824481D02*
Y840927D01*
G01X1111373Y840813D02*
Y824595D01*
G01X1124100Y840286D02*
X1122247Y850788D01*
G01X1125400Y840400D02*
X1123568Y850788D01*
G01X1124100Y826797D02*
Y840286D01*
G01X1125400Y826911D02*
Y840400D01*
G01X1136800Y841386D02*
X1134833Y852539D01*
G01X1136154D02*
X1138100Y841500D01*
G01X1136800Y823886D02*
Y841386D01*
G01X1138100Y841500D02*
Y824000D01*
G01X1137845Y817957D02*
X1136800Y823886D01*
G01X1138100Y824000D02*
X1139166Y817957D01*
G01X1125400Y840400D02*
X1123568Y850788D01*
G01X1124100Y840286D02*
X1122247Y850788D01*
G01X1125400Y826911D02*
Y840400D01*
G01X1124100Y826797D02*
Y840286D01*
G01X1138100Y824000D02*
X1139166Y817957D01*
G01X1137845D02*
X1136800Y823886D01*
G01X1138100Y841500D02*
Y824000D01*
G01X1136800Y823886D02*
Y841386D01*
G01X1136154Y852539D02*
X1138100Y841500D01*
G01X1136800Y841386D02*
X1134833Y852539D01*
G01X1110741Y851884D02*
X1112855Y863872D01*
G01X1111555Y873200D02*
Y863989D01*
G01X1112855Y863872D02*
Y873200D01*
G01Y863872D02*
Y873200D01*
G01X1111555D02*
Y863989D01*
G01X1110741Y851884D02*
X1112855Y863872D01*
G01X1124153Y861594D02*
Y873200D01*
G01X1125453Y861477D02*
Y873200D01*
G01X1122247Y850788D02*
X1124153Y861594D01*
G01X1123568Y850788D02*
X1125453Y861477D01*
G01X1136752Y863424D02*
Y873200D01*
G01X1138052Y873800D02*
Y863306D01*
G01X1134833Y852539D02*
X1136752Y863424D01*
G01X1138052Y863306D02*
X1136154Y852539D01*
G01X1125453Y861477D02*
Y873200D01*
G01X1124153Y861594D02*
Y873200D01*
G01X1123568Y850788D02*
X1125453Y861477D01*
G01X1122247Y850788D02*
X1124153Y861594D01*
G01X1138052Y863306D02*
X1136154Y852539D01*
G01X1134833D02*
X1136752Y863424D01*
G01X1138052Y873800D02*
Y863306D01*
G01X1136752Y863424D02*
Y873200D01*
G01X1152944Y28095D02*
X1145910Y23169D01*
G01X1152010Y29029D02*
X1145400Y24400D01*
G01X1157044Y33951D02*
X1152944Y28095D01*
G01X1155744Y34361D02*
X1152010Y29029D01*
G01X1157044Y48784D02*
Y33951D01*
G01X1155744Y48525D02*
Y34361D01*
G01X1152010Y29029D02*
X1145400Y24400D01*
G01X1152944Y28095D02*
X1145910Y23169D01*
G01X1155744Y34361D02*
X1152010Y29029D01*
G01X1157044Y33951D02*
X1152944Y28095D01*
G01X1155744Y48525D02*
Y34361D01*
G01X1157044Y48784D02*
Y33951D01*
G01X1178391Y73505D02*
X1168999Y75936D01*
G01X1159415Y72603D02*
X1159947Y75619D01*
G01X1157642Y70038D02*
X1158626Y75619D01*
G01X1158963Y70038D02*
X1159415Y72603D01*
G01X1157642Y70038D02*
X1158626Y75619D01*
G01X1159309Y68077D02*
X1158963Y70038D01*
G01X1158028Y67851D02*
X1157642Y70038D01*
G01X1159455Y67248D02*
X1159309Y68077D01*
G01X1158028Y67851D02*
X1157642Y70038D01*
G01X1158233Y66687D02*
X1158028Y67851D01*
G01X1160989Y65373D02*
X1159455Y67248D01*
G01X1160177Y64312D02*
X1158233Y66687D01*
G01X1171659Y60583D02*
X1160989Y65373D01*
G01X1171516Y59222D02*
X1160177Y64312D01*
G01X1173939Y61075D02*
X1171659Y60583D01*
G01X1174453Y59855D02*
X1171516Y59222D01*
G01X1174514Y61456D02*
X1173939Y61075D01*
G01X1175806Y60752D02*
X1174453Y59855D01*
G01X1175088Y61836D02*
X1174514Y61456D01*
G01X1175806Y60752D02*
X1174453Y59855D01*
G01X1177384Y65146D02*
G02X1175088Y61836I-5292J1220D01*
G01X1178651Y64854D02*
G02X1175806Y60752I-6559J1512D01*
G01X1178391Y73505D02*
X1168999Y75936D01*
G01X1157642Y70038D02*
X1158626Y75619D01*
G01X1159415Y72603D02*
X1159947Y75619D01*
G01X1158963Y70038D02*
X1159415Y72603D01*
G01X1158028Y67851D02*
X1157642Y70038D01*
G01X1159309Y68077D02*
X1158963Y70038D01*
G01X1159455Y67248D02*
X1159309Y68077D01*
G01X1158233Y66687D02*
X1158028Y67851D01*
G01X1159455Y67248D02*
X1159309Y68077D01*
G01X1160177Y64312D02*
X1158233Y66687D01*
G01X1160989Y65373D02*
X1159455Y67248D01*
G01X1171516Y59222D02*
X1160177Y64312D01*
G01X1171659Y60583D02*
X1160989Y65373D01*
G01X1174453Y59855D02*
X1171516Y59222D01*
G01X1173939Y61075D02*
X1171659Y60583D01*
G01X1175806Y60752D02*
X1174453Y59855D01*
G01X1174514Y61456D02*
X1173939Y61075D01*
G01X1175088Y61836D02*
X1174514Y61456D01*
G01X1178651Y64854D02*
G02X1175806Y60752I-6559J1512D01*
G01X1177384Y65146D02*
G02X1175088Y61836I-5292J1220D01*
G01X1145545Y72816D02*
X1143888Y74473D01*
G01X1146464Y73736D02*
X1144800Y75400D01*
G01X1145881Y72000D02*
G03X1145544Y72815I-1154J0D01*
G01X1147183Y72000D02*
G03X1146464Y73736I-2455J0D01*
G01X1145881Y71762D02*
Y72000D01*
G01X1147183Y64292D02*
Y72000D01*
G01X1155348Y52879D02*
X1157044Y48784D01*
G01X1154245Y52142D02*
X1155744Y48525D01*
G01X1149963Y58263D02*
X1155348Y52879D01*
G01X1149226Y57161D02*
X1154245Y52142D01*
G01X1146981Y59499D02*
X1149963Y58263D01*
G01X1146722Y58199D02*
X1149226Y57161D01*
G01X1144697Y59499D02*
X1146981D01*
G01X1144955Y58199D02*
X1146722D01*
G01X1146464Y73736D02*
X1144800Y75400D01*
G01X1145545Y72816D02*
X1143888Y74473D01*
G01X1147183Y72000D02*
G03X1146464Y73736I-2455J0D01*
G01X1145881Y72000D02*
G03X1145544Y72815I-1154J0D01*
G01X1147183Y64292D02*
Y72000D01*
G01X1145881Y71762D02*
Y72000D01*
G01X1154245Y52142D02*
X1155744Y48525D01*
G01X1155348Y52879D02*
X1157044Y48784D01*
G01X1149226Y57161D02*
X1154245Y52142D01*
G01X1149963Y58263D02*
X1155348Y52879D01*
G01X1146722Y58199D02*
X1149226Y57161D01*
G01X1146981Y59499D02*
X1149963Y58263D01*
G01X1144955Y58199D02*
X1146722D01*
G01X1144697Y59499D02*
X1146981D01*
G01X1161987Y107867D02*
X1158853Y110062D01*
G01X1163784Y105301D02*
X1161987Y107867D01*
G01X1165015Y105811D02*
X1162921Y108801D01*
G01X1165373Y96291D02*
X1163784Y105301D01*
G01X1166604Y96801D02*
X1165015Y105811D01*
G01X1169007Y91101D02*
X1165373Y96291D01*
G01X1169941Y92035D02*
X1166604Y96801D01*
G01X1172433Y88702D02*
X1169007Y91101D01*
G01X1172943Y89933D02*
X1169941Y92035D01*
G01X1176353Y88011D02*
X1172433Y88702D01*
G01X1176353Y89332D02*
X1172943Y89933D01*
G01X1183686Y89304D02*
X1176353Y88011D01*
G01X1183686Y90625D02*
X1176353Y89332D01*
G01X1150915Y101486D02*
X1145165Y102500D01*
G01X1151425Y102717D02*
X1145279Y103800D01*
G01X1152964Y100051D02*
X1150915Y101486D01*
G01X1155946Y99551D02*
X1151425Y102717D01*
G01X1152965Y100051D02*
X1152964D01*
G01X1155946Y99551D02*
X1151425Y102717D01*
G01X1155012Y98617D02*
X1152965Y100051D01*
G01X1155946Y99551D02*
X1151425Y102717D01*
G01X1162292Y88219D02*
X1155012Y98617D01*
G01X1163523Y88729D02*
X1155946Y99551D01*
G01X1163790Y79727D02*
X1162292Y88219D01*
G01X1164980Y80470D02*
X1163523Y88729D01*
G01X1168999Y75936D02*
X1163790Y79727D01*
G01X1169564Y77133D02*
X1164980Y80470D01*
G01X1178376Y74852D02*
X1169564Y77133D01*
G01X1156378Y86327D02*
X1152453Y89078D01*
G01X1155444Y85394D02*
X1151943Y87847D01*
G01X1156509Y86141D02*
X1156378Y86327D01*
G01X1157392Y82612D02*
X1155444Y85394D01*
G01X1158623Y83122D02*
X1156509Y86140D01*
G01X1157392Y82612D02*
X1155444Y85394D01*
G01X1159947Y75619D02*
X1158623Y83122D01*
G01X1158626Y75619D02*
X1157392Y82612D01*
G01X1161987Y107867D02*
X1158853Y110062D01*
G01X1165015Y105811D02*
X1162921Y108801D01*
G01X1163784Y105301D02*
X1161987Y107867D01*
G01X1166604Y96801D02*
X1165015Y105811D01*
G01X1165373Y96291D02*
X1163784Y105301D01*
G01X1169941Y92035D02*
X1166604Y96801D01*
G01X1169007Y91101D02*
X1165373Y96291D01*
G01X1172943Y89933D02*
X1169941Y92035D01*
G01X1172433Y88702D02*
X1169007Y91101D01*
G01X1176353Y89332D02*
X1172943Y89933D01*
G01X1176353Y88011D02*
X1172433Y88702D01*
G01X1183686Y90625D02*
X1176353Y89332D01*
G01X1183686Y89304D02*
X1176353Y88011D01*
G01X1151425Y102717D02*
X1145279Y103800D01*
G01X1150915Y101486D02*
X1145165Y102500D01*
G01X1155946Y99551D02*
X1151425Y102717D01*
G01X1152964Y100051D02*
X1150915Y101486D01*
G01X1152965Y100051D02*
X1152964D01*
G01X1155012Y98617D02*
X1152965Y100051D01*
G01X1163523Y88729D02*
X1155946Y99551D01*
G01X1162292Y88219D02*
X1155012Y98617D01*
G01X1164980Y80470D02*
X1163523Y88729D01*
G01X1163790Y79727D02*
X1162292Y88219D01*
G01X1169564Y77133D02*
X1164980Y80470D01*
G01X1168999Y75936D02*
X1163790Y79727D01*
G01X1178376Y74852D02*
X1169564Y77133D01*
G01X1155444Y85394D02*
X1151943Y87847D01*
G01X1156378Y86327D02*
X1152453Y89078D01*
G01X1157392Y82612D02*
X1155444Y85394D01*
G01X1156509Y86141D02*
X1156378Y86327D01*
G01X1158623Y83122D02*
X1156509Y86140D01*
G01X1158626Y75619D02*
X1157392Y82612D01*
G01X1159947Y75619D02*
X1158623Y83122D01*
G01X1143888Y74473D02*
G03X1143637Y74683I-1303J-1302D01*
G01X1144800Y75400D02*
G03X1144379Y75752I-2174J-2172D01*
G01X1143888Y74473D02*
G03X1143637Y74683I-1303J-1302D01*
G01X1144800Y75400D02*
G03X1144379Y75752I-2174J-2172D01*
G01X1143888Y74473D02*
G03X1143637Y74683I-1303J-1302D01*
G01X1147762Y124844D02*
X1145458Y124442D01*
G01X1155629Y127535D02*
X1147539Y126125D01*
G01X1157202Y126489D02*
X1147762Y124844D01*
G01X1157203Y127809D02*
X1155629Y127535D01*
G01X1157202Y126489D02*
X1147762Y124844D01*
G01X1165208Y126399D02*
X1157203Y127809D01*
G01X1173220Y123665D02*
X1157202Y126489D01*
G01X1173220Y124986D02*
X1165208Y126399D01*
G01X1173220Y123665D02*
X1157202Y126489D01*
G01X1185636Y127175D02*
X1173220Y124986D01*
G01X1185636Y125854D02*
X1173220Y123665D01*
G01X1174310Y114941D02*
X1185783Y116963D01*
G01Y118284D02*
X1174309Y116262D01*
G01X1165933Y116418D02*
X1174310Y114941D01*
G01X1174309Y116262D02*
X1166445Y117648D01*
G01X1163329Y118239D02*
X1165933Y116418D01*
G01X1166445Y117648D02*
X1162661Y120295D01*
G01X1162151Y119064D02*
X1163329Y118239D01*
G01X1166445Y117648D02*
X1162661Y120295D01*
G01X1157620Y119863D02*
X1162151Y119064D01*
G01X1160111Y120745D02*
X1157620Y121184D01*
G01X1160997Y120589D02*
X1160111Y120745D01*
G01X1162661Y120295D02*
X1160997Y120589D01*
G01X1159216Y114630D02*
X1153450Y115784D01*
G01Y117110D02*
X1159471Y115905D01*
G01X1164977Y113478D02*
X1159216Y114630D01*
G01X1165231Y114754D02*
X1165500Y114700D01*
G01X1159471Y115905D02*
X1165231Y114753D01*
G01X1168125Y111274D02*
X1164977Y113478D01*
G01X1165500Y114700D02*
X1168635Y112505D01*
G01X1171500Y110679D02*
X1168125Y111274D01*
G01X1168635Y112505D02*
X1171500Y112000D01*
G01X1184059Y112893D02*
X1171500Y110679D01*
G01Y112000D02*
X1184059Y114214D01*
G01X1147762Y124844D02*
X1145458Y124442D01*
G01X1157202Y126489D02*
X1147762Y124844D01*
G01X1155629Y127535D02*
X1147539Y126125D01*
G01X1157203Y127809D02*
X1155629Y127535D01*
G01X1173220Y123665D02*
X1157202Y126489D01*
G01X1165208Y126399D02*
X1157203Y127809D01*
G01X1173220Y124986D02*
X1165208Y126399D01*
G01X1185636Y125854D02*
X1173220Y123665D01*
G01X1185636Y127175D02*
X1173220Y124986D01*
G01X1164667Y122074D02*
X1157917Y123263D01*
G01X1165179Y123304D02*
X1157917Y124584D01*
G01X1164668Y122074D02*
X1164667D01*
G01X1165179Y123304D02*
X1157917Y124584D01*
G01X1169011Y120621D02*
X1165179Y123304D01*
G01X1168501Y119390D02*
X1164668Y122074D01*
G01X1169011Y120621D02*
X1165179Y123304D01*
G01X1174550Y118324D02*
X1168501Y119390D01*
G01X1174550Y119645D02*
X1169011Y120621D01*
G01X1189506Y120961D02*
X1174550Y118324D01*
G01X1189506Y122282D02*
X1174550Y119645D01*
G01X1160111Y120745D02*
X1157620Y121184D01*
G01Y119863D02*
X1162151Y119064D01*
G01X1160997Y120589D02*
X1160111Y120745D01*
G01X1157620Y119863D02*
X1162151Y119064D01*
G01X1162661Y120295D02*
X1160997Y120589D01*
G01X1157620Y119863D02*
X1162151Y119064D01*
G01X1166445Y117648D02*
X1162661Y120295D01*
G01X1163329Y118239D02*
X1165933Y116418D01*
G01X1162151Y119064D02*
X1163329Y118239D01*
G01X1174309Y116262D02*
X1166445Y117648D01*
G01X1165933Y116418D02*
X1174310Y114941D01*
G01X1185783Y118284D02*
X1174309Y116262D01*
G01X1174310Y114941D02*
X1185783Y116963D01*
G01X1171500Y112000D02*
X1184059Y114214D01*
G01Y112893D02*
X1171500Y110679D01*
G01X1168635Y112505D02*
X1171500Y112000D01*
G01Y110679D02*
X1168125Y111274D01*
G01X1165500Y114700D02*
X1168635Y112505D01*
G01X1168125Y111274D02*
X1164977Y113478D01*
G01X1165231Y114754D02*
X1165500Y114700D01*
G01X1164977Y113478D02*
X1159216Y114630D01*
G01X1159471Y115905D02*
X1165231Y114753D01*
G01X1164977Y113478D02*
X1159216Y114630D01*
G01X1153450Y117110D02*
X1159471Y115905D01*
G01X1159216Y114630D02*
X1153450Y115784D01*
G01X1165179Y123304D02*
X1157917Y124584D01*
G01X1164667Y122074D02*
X1157917Y123263D01*
G01X1164668Y122074D02*
X1164667D01*
G01X1169011Y120621D02*
X1165179Y123304D01*
G01X1164668Y122074D02*
X1164667D01*
G01X1168501Y119390D02*
X1164668Y122074D01*
G01X1174550Y119645D02*
X1169011Y120621D01*
G01X1174550Y118324D02*
X1168501Y119390D01*
G01X1189506Y122282D02*
X1174550Y119645D01*
G01X1189506Y120961D02*
X1174550Y118324D01*
G01X1158853Y110062D02*
X1152263Y111224D01*
G01X1159363Y111293D02*
X1152263Y112545D01*
G01X1162921Y108801D02*
X1159363Y111293D01*
G01D02*
X1152263Y112545D01*
G01X1158853Y110062D02*
X1152263Y111224D01*
G01X1162921Y108801D02*
X1159363Y111293D01*
G01X1183220Y176078D02*
X1158060Y171246D01*
G01X1178867Y170111D02*
X1155177Y165933D01*
G01X1187815Y161099D02*
X1172708Y164310D01*
G01X1172713Y165638D02*
X1188321Y162321D01*
G01X1163481Y158212D02*
X1153037Y156081D01*
G01X1173928Y160346D02*
X1163481Y158213D01*
G01X1185247Y157940D02*
X1173928Y160346D01*
G01X1185763Y159160D02*
X1173933Y161674D01*
G01X1183220Y176078D02*
X1158060Y171246D01*
G01X1178867Y170111D02*
X1155177Y165933D01*
G01X1172713Y165638D02*
X1188321Y162321D01*
G01X1187815Y161099D02*
X1172708Y164310D01*
G01X1163481Y158212D02*
X1153037Y156081D01*
G01X1173928Y160346D02*
X1163481Y158213D01*
G01X1185763Y159160D02*
X1173933Y161674D01*
G01X1185247Y157940D02*
X1173928Y160346D01*
G01X1225742Y710048D02*
X1145626Y261700D01*
G01X1226972Y709537D02*
X1146856Y261190D01*
G01X1148460Y260248D02*
X1233532Y709272D01*
G01X1149685Y259730D02*
X1234758Y708755D01*
G01X1226972Y709537D02*
X1146856Y261190D01*
G01X1225742Y710048D02*
X1145626Y261700D01*
G01X1149685Y259730D02*
X1234758Y708755D01*
G01X1148460Y260248D02*
X1233532Y709272D01*
G01X1161771Y720780D02*
X1147710Y800515D01*
G01X1149031D02*
X1163092Y720780D01*
G01X1174026Y735665D02*
X1162019Y803770D01*
G01X1175347Y735665D02*
X1163340Y803770D01*
G01X1149031Y800515D02*
X1163092Y720780D01*
G01X1161771D02*
X1147710Y800515D01*
G01X1175347Y735665D02*
X1163340Y803770D01*
G01X1174026Y735665D02*
X1162019Y803770D01*
G01X1147710Y800515D02*
X1150926Y818755D01*
G01X1152247D02*
X1149031Y800515D01*
G01X1162019Y803770D02*
X1167729Y836207D01*
G01X1163340Y803770D02*
X1169050Y836207D01*
G01X1152247Y818755D02*
X1149031Y800515D01*
G01X1147710D02*
X1150926Y818755D01*
G01X1163340Y803770D02*
X1169050Y836207D01*
G01X1162019Y803770D02*
X1167729Y836207D01*
G01X1148499Y847073D02*
X1150099Y856149D01*
G01X1151420D02*
X1149820Y847073D01*
G01X1149520Y841286D02*
X1148499Y847073D01*
G01X1149820D02*
X1150820Y841400D01*
G01X1149520Y826731D02*
Y841286D01*
G01X1150820Y841400D02*
Y826845D01*
G01X1150926Y818755D02*
X1149520Y826731D01*
G01X1150820Y826845D02*
X1152247Y818755D01*
G01X1167729Y836207D02*
X1161949Y868989D01*
G01X1169050Y836207D02*
X1163249Y869106D01*
G01X1150820Y826845D02*
X1152247Y818755D01*
G01X1150926D02*
X1149520Y826731D01*
G01X1150820Y841400D02*
Y826845D01*
G01X1149520Y826731D02*
Y841286D01*
G01X1149820Y847073D02*
X1150820Y841400D01*
G01X1149520Y841286D02*
X1148499Y847073D01*
G01X1151420Y856149D02*
X1149820Y847073D01*
G01X1148499D02*
X1150099Y856149D01*
G01X1169050Y836207D02*
X1163249Y869106D01*
G01X1167729Y836207D02*
X1161949Y868989D01*
G01X1149350Y860397D02*
Y873200D01*
G01X1150650D02*
Y860515D01*
G01X1150099Y856149D02*
X1149350Y860397D01*
G01X1150650Y860515D02*
X1151420Y856149D01*
G01X1161949Y868989D02*
Y873200D01*
G01X1163249Y869106D02*
Y873200D01*
G01X1150650Y860515D02*
X1151420Y856149D01*
G01X1150099D02*
X1149350Y860397D01*
G01X1150650Y873200D02*
Y860515D01*
G01X1149350Y860397D02*
Y873200D01*
G01X1163249Y869106D02*
Y873200D01*
G01X1161949Y868989D02*
Y873200D01*
G01X1205200Y72361D02*
X1211522Y66039D01*
G01X1212061Y67339D02*
X1206500Y72900D01*
G01X1205200Y86261D02*
Y72361D01*
G01X1206500Y72900D02*
Y86671D01*
G01X1201200Y69361D02*
Y84576D01*
G01X1202500Y84986D02*
Y69900D01*
G01X1210661Y59900D02*
X1201200Y69361D01*
G01X1202500Y69900D02*
X1211200Y61200D01*
G01X1222161Y59900D02*
X1210661D01*
G01X1206500Y72900D02*
Y86671D01*
G01X1205200Y86261D02*
Y72361D01*
G01X1212061Y67339D02*
X1206500Y72900D01*
G01X1205200Y72361D02*
X1211522Y66039D01*
G01X1222161Y59900D02*
X1210661D01*
G01X1202500Y69900D02*
X1211200Y61200D01*
G01X1210661Y59900D02*
X1201200Y69361D01*
G01X1202500Y84986D02*
Y69900D01*
G01X1201200Y69361D02*
Y84576D01*
G01X1196800Y67395D02*
Y81712D01*
G01X1198100Y67276D02*
Y81712D01*
G01X1195570Y60367D02*
X1196800Y67395D01*
G01X1196781Y59740D02*
X1198100Y67276D01*
G01X1190592Y55389D02*
X1195570Y60367D01*
G01X1191512Y54469D02*
X1196780Y59738D01*
G01X1181181Y74295D02*
X1178391Y73505D01*
G01X1188799Y73436D02*
X1186756Y74461D01*
G01X1189783Y72212D02*
X1188799Y73436D01*
G01X1190304Y73639D02*
X1189636Y74472D01*
G01X1190796Y73027D02*
X1190304Y73639D01*
G01X1189664Y68932D02*
G03X1189783Y72212I-1834J1709D01*
G01X1190615Y68045D02*
G03X1190796Y73027I-2785J2595D01*
G01X1189285Y68656D02*
G03X1189664Y68932I-521J1113D01*
G01X1189836Y67477D02*
G03X1190616Y68045I-1072J2291D01*
G01X1189319Y67300D02*
G03X1189836Y67477I-556J2468D01*
G01X1177735Y66015D02*
G03X1177384Y65146I2549J-1535D01*
G01X1178849Y65344D02*
G03X1178652Y64854I1436J-862D01*
G01X1198100Y67276D02*
Y81712D01*
G01X1196800Y67395D02*
Y81712D01*
G01X1196781Y59740D02*
X1198100Y67276D01*
G01X1195570Y60367D02*
X1196800Y67395D01*
G01X1191512Y54469D02*
X1196780Y59738D01*
G01X1190592Y55389D02*
X1195570Y60367D01*
G01X1181181Y74295D02*
X1178391Y73505D01*
G01X1188799Y73436D02*
X1186756Y74461D01*
G01X1190304Y73639D02*
X1189636Y74472D01*
G01X1189783Y72212D02*
X1188799Y73436D01*
G01X1190796Y73027D02*
X1190304Y73639D01*
G01X1189783Y72212D02*
X1188799Y73436D01*
G01X1190615Y68045D02*
G03X1190796Y73027I-2785J2595D01*
G01X1189664Y68932D02*
G03X1189783Y72212I-1834J1709D01*
G01X1189836Y67477D02*
G03X1190616Y68045I-1072J2291D01*
G01X1189285Y68656D02*
G03X1189664Y68932I-521J1113D01*
G01X1189319Y67300D02*
G03X1189836Y67477I-556J2468D01*
G01X1189285Y68656D02*
G03X1189664Y68932I-521J1113D01*
G01X1178849Y65344D02*
G03X1178652Y64854I1436J-862D01*
G01X1177735Y66015D02*
G03X1177384Y65146I2549J-1535D01*
G01X1202179Y90576D02*
X1205200Y86261D01*
G01X1206500Y86671D02*
X1203410Y91086D01*
G01X1200861Y98050D02*
X1202179Y90576D01*
G01X1203410Y91086D02*
X1202182Y98050D01*
G01X1202114Y105159D02*
X1200861Y98050D01*
G01X1202182D02*
X1203435Y105159D01*
G01X1201320Y109669D02*
X1202114Y105159D01*
G01X1203435D02*
X1202459Y110703D01*
G01X1203435Y105159D02*
X1202459Y110703D01*
G01X1197075Y107389D02*
X1195629Y109455D01*
G01X1196563Y110389D02*
X1198306Y107899D01*
G01X1197555Y104665D02*
X1197075Y107389D01*
G01X1198306Y107899D02*
X1198876Y104665D01*
G01X1196492Y98632D02*
X1197555Y104665D01*
G01X1198876D02*
X1197813Y98632D01*
G01X1198221Y88831D02*
X1196492Y98632D01*
G01X1197813D02*
X1199452Y89341D01*
G01X1201200Y84576D02*
X1198221Y88831D01*
G01X1199452Y89341D02*
X1202500Y84986D01*
G01X1206562Y106944D02*
X1205600Y112400D01*
G01X1207883Y106944D02*
X1206831Y112910D01*
G01X1204941Y97748D02*
X1206562Y106944D01*
G01X1206262Y97748D02*
X1207883Y106944D01*
G01X1205330Y95541D02*
X1204941Y97748D01*
G01X1206561Y96051D02*
X1206262Y97748D01*
G01X1208141Y91526D02*
X1205330Y95541D01*
G01X1209372Y92036D02*
X1206561Y96051D01*
G01X1209066Y86276D02*
X1208141Y91526D01*
G01X1210387Y86276D02*
X1209372Y92036D01*
G01X1208855Y85076D02*
X1209066Y86276D01*
G01X1210021Y84200D02*
X1210387Y86276D01*
G01X1208700Y84200D02*
X1208855Y85076D01*
G01X1210021Y84200D02*
X1210387Y86276D01*
G01X1209464Y79865D02*
X1208700Y84200D01*
G01X1210695Y80375D02*
X1210021Y84200D01*
G01X1211049Y77602D02*
X1209464Y79865D01*
G01X1212022Y78480D02*
X1210695Y80375D01*
G01X1203435Y105159D02*
X1202459Y110703D01*
G01X1201320Y109669D02*
X1202114Y105159D01*
G01X1202182Y98050D02*
X1203435Y105159D01*
G01X1202114D02*
X1200861Y98050D01*
G01X1203410Y91086D02*
X1202182Y98050D01*
G01X1200861D02*
X1202179Y90576D01*
G01X1206500Y86671D02*
X1203410Y91086D01*
G01X1202179Y90576D02*
X1205200Y86261D01*
G01X1199452Y89341D02*
X1202500Y84986D01*
G01X1201200Y84576D02*
X1198221Y88831D01*
G01X1197813Y98632D02*
X1199452Y89341D01*
G01X1198221Y88831D02*
X1196492Y98632D01*
G01X1198876Y104665D02*
X1197813Y98632D01*
G01X1196492D02*
X1197555Y104665D01*
G01X1198306Y107899D02*
X1198876Y104665D01*
G01X1197555D02*
X1197075Y107389D01*
G01X1196563Y110389D02*
X1198306Y107899D01*
G01X1197075Y107389D02*
X1195629Y109455D01*
G01X1207883Y106944D02*
X1206831Y112910D01*
G01X1206562Y106944D02*
X1205600Y112400D01*
G01X1206262Y97748D02*
X1207883Y106944D01*
G01X1204941Y97748D02*
X1206562Y106944D01*
G01X1206561Y96051D02*
X1206262Y97748D01*
G01X1205330Y95541D02*
X1204941Y97748D01*
G01X1209372Y92036D02*
X1206561Y96051D01*
G01X1208141Y91526D02*
X1205330Y95541D01*
G01X1210387Y86276D02*
X1209372Y92036D01*
G01X1209066Y86276D02*
X1208141Y91526D01*
G01X1210021Y84200D02*
X1210387Y86276D01*
G01X1208855Y85076D02*
X1209066Y86276D01*
G01X1208700Y84200D02*
X1208855Y85076D01*
G01X1210695Y80375D02*
X1210021Y84200D01*
G01X1209464Y79865D02*
X1208700Y84200D01*
G01X1212022Y78480D02*
X1210695Y80375D01*
G01X1211049Y77602D02*
X1209464Y79865D01*
G01X1191130Y87992D02*
X1183686Y89304D01*
G01X1191640Y89223D02*
X1183686Y90625D01*
G01X1194146Y85880D02*
X1191130Y87992D01*
G01X1195080Y86814D02*
X1191640Y89223D01*
G01X1196583Y82400D02*
X1194146Y85880D01*
G01X1197648Y83146D02*
X1195080Y86814D01*
G01X1196800Y81712D02*
G03X1196583Y82400I-1201J0D01*
G01X1198100Y81712D02*
G03X1197648Y83146I-2501J0D01*
G01X1183277Y76240D02*
X1178376Y74852D01*
G01X1183365Y74913D02*
X1181181Y74295D01*
G01X1183277Y76240D02*
X1178376Y74852D01*
G01X1184219Y74800D02*
X1183365Y74913D01*
G01X1183277Y76240D02*
X1178376Y74852D01*
G01X1185236Y75977D02*
X1183277Y76240D01*
G01X1186756Y74461D02*
X1184219Y74800D01*
G01X1185236Y75977D02*
X1183277Y76240D01*
G01X1187145Y75721D02*
X1185236Y75977D01*
G01X1189636Y74472D02*
X1187145Y75721D01*
G01X1191640Y89223D02*
X1183686Y90625D01*
G01X1191130Y87992D02*
X1183686Y89304D01*
G01X1195080Y86814D02*
X1191640Y89223D01*
G01X1194146Y85880D02*
X1191130Y87992D01*
G01X1197648Y83146D02*
X1195080Y86814D01*
G01X1196583Y82400D02*
X1194146Y85880D01*
G01X1198100Y81712D02*
G03X1197648Y83146I-2501J0D01*
G01X1196800Y81712D02*
G03X1196583Y82400I-1201J0D01*
G01X1183277Y76240D02*
X1178376Y74852D01*
G01X1183365Y74913D02*
X1181181Y74295D01*
G01X1184219Y74800D02*
X1183365Y74913D01*
G01X1185236Y75977D02*
X1183277Y76240D01*
G01X1184219Y74800D02*
X1183365Y74913D01*
G01X1186756Y74461D02*
X1184219Y74800D01*
G01X1187145Y75721D02*
X1185236Y75977D01*
G01X1186756Y74461D02*
X1184219Y74800D01*
G01X1189636Y74472D02*
X1187145Y75721D01*
G01X1218738Y124995D02*
X1206338Y143787D01*
G01X1219530Y126156D02*
X1207280Y144722D01*
G01X1219530Y126156D02*
X1207280Y144722D01*
G01X1218738Y124995D02*
X1206338Y143787D01*
G01X1220908Y120956D02*
X1185636Y127175D01*
G01X1220398Y119725D02*
X1185636Y125854D01*
G01X1201228Y110193D02*
X1201320Y109669D01*
G01X1199699Y112375D02*
X1201228Y110193D01*
G01X1202459Y110703D02*
X1200697Y113218D01*
G01X1198043Y114013D02*
X1199699Y112375D01*
G01X1200697Y113218D02*
X1198879Y115015D01*
G01X1196534Y115068D02*
X1198043Y114013D01*
G01X1198879Y115015D02*
X1197044Y116299D01*
G01X1193815Y115547D02*
X1196534Y115068D01*
G01X1197044Y116299D02*
X1185783Y118284D01*
G01X1191095Y116026D02*
X1193815Y115547D01*
G01X1197044Y116299D02*
X1185783Y118284D01*
G01X1189804Y116253D02*
X1191095Y116026D01*
G01X1197044Y116299D02*
X1185783Y118284D01*
G01Y116963D02*
X1189804Y116253D01*
G01X1197044Y116299D02*
X1185783Y118284D01*
G01X1192959Y111324D02*
X1184059Y112893D01*
G01Y114214D02*
X1193469Y112555D01*
G01X1195629Y109455D02*
X1192959Y111324D01*
G01X1193469Y112555D02*
X1196563Y110389D01*
G01X1220398Y119725D02*
X1185636Y125854D01*
G01X1220908Y120956D02*
X1185636Y127175D01*
G01X1198805Y119321D02*
X1189506Y120961D01*
G01X1199315Y120552D02*
X1189506Y122282D01*
G01X1202627Y116645D02*
X1198805Y119321D01*
G01X1203561Y117579D02*
X1199315Y120552D01*
G01X1205600Y112400D02*
X1202627Y116645D01*
G01X1206831Y112910D02*
X1203561Y117579D01*
G01X1197044Y116299D02*
X1185783Y118284D01*
G01X1193815Y115547D02*
X1196534Y115068D01*
G01X1191095Y116026D02*
X1193815Y115547D01*
G01X1189804Y116253D02*
X1191095Y116026D01*
G01X1185783Y116963D02*
X1189804Y116253D01*
G01X1198879Y115015D02*
X1197044Y116299D01*
G01X1196534Y115068D02*
X1198043Y114013D01*
G01X1200697Y113218D02*
X1198879Y115015D01*
G01X1198043Y114013D02*
X1199699Y112375D01*
G01X1202459Y110703D02*
X1200697Y113218D01*
G01X1199699Y112375D02*
X1201228Y110193D01*
G01D02*
X1201320Y109669D01*
G01X1193469Y112555D02*
X1196563Y110389D01*
G01X1195629Y109455D02*
X1192959Y111324D01*
G01X1184059Y114214D02*
X1193469Y112555D01*
G01X1192959Y111324D02*
X1184059Y112893D01*
G01X1199315Y120552D02*
X1189506Y122282D01*
G01X1198805Y119321D02*
X1189506Y120961D01*
G01X1203561Y117579D02*
X1199315Y120552D01*
G01X1202627Y116645D02*
X1198805Y119321D01*
G01X1206831Y112910D02*
X1203561Y117579D01*
G01X1205600Y112400D02*
X1202627Y116645D01*
G01X1280433Y154086D02*
X1183207Y174751D01*
G01X1280939Y155308D02*
X1183220Y176078D01*
G01X1255565Y155265D02*
X1178867Y168790D01*
G01X1256052Y156500D02*
X1178867Y170111D01*
G01X1202071Y151841D02*
X1187815Y161099D01*
G01X1188321Y162321D02*
X1202780Y152931D01*
G01X1202554Y151650D02*
X1202262D01*
G01X1202780Y152931D02*
X1220219Y149855D01*
G01X1220156Y148545D02*
X1202554Y151650D01*
G01X1202780Y152931D02*
X1220219Y149855D01*
G01X1202780Y152931D02*
X1220219Y149855D01*
G01X1202780Y152931D02*
X1220219Y149855D01*
G01X1206338Y143787D02*
X1185247Y157940D01*
G01X1207280Y144722D02*
X1185763Y159160D01*
G01X1280939Y155308D02*
X1183220Y176078D01*
G01X1280433Y154086D02*
X1183207Y174751D01*
G01X1256052Y156500D02*
X1178867Y170111D01*
G01X1255565Y155265D02*
X1178867Y168790D01*
G01X1220156Y148545D02*
X1202554Y151650D01*
G01X1220156Y148545D02*
X1202554Y151650D01*
G01X1202780Y152931D02*
X1220219Y149855D01*
G01X1202554Y151650D02*
X1202262D01*
G01X1220156Y148545D02*
X1202554Y151650D01*
G01X1188321Y162321D02*
X1202780Y152931D01*
G01X1202071Y151841D02*
X1187815Y161099D01*
G01X1207280Y144722D02*
X1185763Y159160D01*
G01X1206338Y143787D02*
X1185247Y157940D01*
G01X1181254Y807744D02*
X1187388Y772956D01*
G01X1182575Y807744D02*
X1188709Y772956D01*
G01X1182575Y807744D02*
X1188709Y772956D01*
G01X1181254Y807744D02*
X1187388Y772956D01*
G01X1238769Y814510D02*
X1210639Y774336D01*
G01X1238769Y814510D02*
X1210639Y774336D01*
G01X1183727Y821762D02*
X1181254Y807744D01*
G01X1185027Y821648D02*
X1182575Y807744D01*
G01X1195020Y841248D02*
X1200658Y809279D01*
G01X1201979D02*
X1196341Y841248D01*
G01X1185027Y821648D02*
X1182575Y807744D01*
G01X1183727Y821762D02*
X1181254Y807744D01*
G01X1201979Y809279D02*
X1196341Y841248D01*
G01X1195020D02*
X1200658Y809279D01*
G01X1183727Y841886D02*
Y821762D01*
G01X1185027Y842000D02*
Y821648D01*
G01X1182635Y848074D02*
X1183727Y841886D01*
G01X1183956Y848074D02*
X1185027Y842000D01*
G01X1184122Y856509D02*
X1182635Y848074D01*
G01X1184759Y852632D02*
X1183956Y848074D01*
G01X1196594Y850174D02*
X1195020Y841248D01*
G01X1196341D02*
X1197894Y850060D01*
G01D02*
Y864530D01*
G01X1185027Y842000D02*
Y821648D01*
G01X1183727Y841886D02*
Y821762D01*
G01X1183956Y848074D02*
X1185027Y842000D01*
G01X1182635Y848074D02*
X1183727Y841886D01*
G01X1184759Y852632D02*
X1183956Y848074D01*
G01X1184122Y856509D02*
X1182635Y848074D01*
G01X1184122Y856509D02*
X1182635Y848074D01*
G01X1197894Y850060D02*
Y864530D01*
G01X1196341Y841248D02*
X1197894Y850060D01*
G01X1196594Y850174D02*
X1195020Y841248D01*
G01X1185443Y856509D02*
X1184759Y852632D01*
G01X1183010Y862817D02*
X1184122Y856509D01*
G01X1184331Y862817D02*
X1185443Y856509D01*
G01X1183996Y868409D02*
X1183010Y862817D01*
G01X1185296Y868295D02*
X1184331Y862817D01*
G01X1183996Y873200D02*
Y868409D01*
G01X1185296Y873200D02*
Y868295D01*
G01X1196594Y864400D02*
Y850174D01*
G01X1185443Y856509D02*
X1184759Y852632D01*
G01X1184331Y862817D02*
X1185443Y856509D01*
G01X1183010Y862817D02*
X1184122Y856509D01*
G01X1185296Y868295D02*
X1184331Y862817D01*
G01X1183996Y868409D02*
X1183010Y862817D01*
G01X1185296Y873200D02*
Y868295D01*
G01X1183996Y873200D02*
Y868409D01*
G01X1196594Y864400D02*
Y850174D01*
G01X1241000Y66199D02*
Y93571D01*
G01X1239700Y66200D02*
Y93700D01*
G01X1240054Y63915D02*
G03X1241000Y66199I-2285J2284D01*
G01X1239134Y64835D02*
G03X1239700Y66200I-1365J1366D01*
G01X1235419Y59280D02*
X1240054Y63915D01*
G01X1234499Y60199D02*
X1239134Y64835D01*
G01X1234793Y57769D02*
G02X1235419Y59280I2137J0D01*
G01X1233493Y57770D02*
G02X1234499Y60199I3437J-1D01*
G01X1234793Y54992D02*
Y57769D01*
G01X1233493Y55001D02*
Y57770D01*
G01X1234792Y54940D02*
G03X1234793Y54992I-2516J74D01*
G01X1233158Y54162D02*
G03X1233492Y54968I-806J806D01*
G01X1234792Y54923D02*
G03Y54940I-2516J9D01*
G01X1233158Y54162D02*
G03X1233492Y54968I-806J806D01*
G01X1234109Y53274D02*
G03X1234792Y54923I-1833J1725D01*
G01X1233492Y54968D02*
G03X1233493Y55001I-1216J53D01*
G01X1233158Y54162D02*
G03X1233492Y54968I-806J806D01*
G01X1224555Y68656D02*
G02X1224126Y68140I-1730J1002D01*
G01X1225681Y68004D02*
G03X1226122Y69519I-2856J1653D01*
G01X1224823Y69574D02*
G02X1224555Y68656I-1998J85D01*
G01X1225681Y68004D02*
G03X1226122Y69519I-2856J1653D01*
G01X1224531Y71395D02*
G02X1224823Y69574I-4308J-1625D01*
G01X1226122Y69519D02*
G03X1225748Y71855I-5899J254D01*
G01X1222772Y72610D02*
G02X1224531Y71395I0J-1881D01*
G01X1225748Y71855D02*
G03X1222772Y73910I-2975J-1126D01*
G01X1220898Y72610D02*
X1222772D01*
G01Y73910D02*
X1220897D01*
G01X1220273Y72470D02*
G02X1220898Y72610I626J-1331D01*
G01X1219721Y73648D02*
G03X1218937Y73098I1178J-2513D01*
G01X1220897Y73910D02*
G03X1219721Y73648I0J-2771D01*
G01X1219858Y72180D02*
G02X1220273Y72470I1040J-1046D01*
G01X1219721Y73648D02*
G03X1218937Y73098I1178J-2513D01*
G01X1220897Y73910D02*
G03X1219721Y73648I0J-2771D01*
G01X1219742Y72062D02*
X1219858Y72180D01*
G01X1218820Y72980D02*
X1218520Y72680D01*
G01X1219440Y71760D02*
X1219742Y72062D01*
G01X1218519Y72680D02*
X1218422Y72583D01*
G01X1218520Y72680D02*
X1218519D01*
G01X1218820Y72980D02*
X1218520Y72680D01*
G01X1218937Y73098D02*
X1218820Y72980D01*
G01X1219342Y71663D02*
X1219439Y71760D01*
G01X1218820Y72980D02*
X1218520Y72680D01*
G01X1219297Y71616D02*
G02X1219342Y71663I784J-706D01*
G01X1218325Y72480D02*
G03X1217845Y71646I1759J-1567D01*
G01X1219081Y71241D02*
G02X1219297Y71616I1003J-328D01*
G01X1218325Y72480D02*
G03X1217845Y71646I1759J-1567D01*
G01X1219032Y71091D02*
X1219081Y71241D01*
G01X1217845Y71646D02*
X1217706Y71221D01*
G01X1218942Y70816D02*
X1219032Y71091D01*
G01X1217845Y71646D02*
X1217706Y71221D01*
G01X1218345Y69844D02*
G03X1218942Y70816I-1737J1736D01*
G01X1217706Y71221D02*
G02X1217425Y70764I-1098J360D01*
G01X1218300Y69800D02*
X1218345Y69844D01*
G01X1217425Y70764D02*
X1214000Y67339D01*
G01X1214539Y66039D02*
X1218300Y69800D01*
G01X1217425Y70764D02*
X1214000Y67339D01*
G01X1211522Y66039D02*
X1214539D01*
G01X1214000Y67339D02*
X1212061D01*
G01X1211200Y61200D02*
X1222700D01*
G01X1224635Y57426D02*
X1222161Y59900D01*
G01X1222700Y61200D02*
X1225935Y57965D01*
G01X1224635Y54395D02*
Y57426D01*
G01X1225935Y57965D02*
Y54394D01*
G01X1224123Y53159D02*
G03X1224635Y54395I-1236J1236D01*
G01X1225554Y52908D02*
G02X1225276Y52486I-2714J1486D01*
G01X1225935Y54394D02*
G02X1225554Y52908I-3095J2D01*
G01X1239700Y66200D02*
Y93700D01*
G01X1241000Y66199D02*
Y93571D01*
G01X1239134Y64835D02*
G03X1239700Y66200I-1365J1366D01*
G01X1240054Y63915D02*
G03X1241000Y66199I-2285J2284D01*
G01X1234499Y60199D02*
X1239134Y64835D01*
G01X1235419Y59280D02*
X1240054Y63915D01*
G01X1233493Y57770D02*
G02X1234499Y60199I3437J-1D01*
G01X1234793Y57769D02*
G02X1235419Y59280I2137J0D01*
G01X1233493Y55001D02*
Y57770D01*
G01X1234793Y54992D02*
Y57769D01*
G01X1233492Y54968D02*
G03X1233493Y55001I-1216J53D01*
G01X1234109Y53274D02*
G03X1234792Y54923I-1833J1725D01*
G01X1233158Y54162D02*
G03X1233492Y54968I-806J806D01*
G01X1234792Y54940D02*
G03X1234793Y54992I-2516J74D01*
G01X1234792Y54923D02*
G03Y54940I-2516J9D01*
G01X1234109Y53274D02*
G03X1234792Y54923I-1833J1725D01*
G01X1233493Y72471D02*
G03X1232761Y74239I-2501J0D01*
G01X1234793Y72471D02*
G03X1233681Y75159I-3802J1D01*
G01X1233493Y70291D02*
Y72471D01*
G01X1234793Y70291D02*
Y72471D01*
G01X1233367Y69656D02*
G03X1233493Y70291I-1537J635D01*
G01X1234569Y69160D02*
G03X1234793Y70291I-2739J1130D01*
G01X1233230Y69324D02*
X1233367Y69656D01*
G01X1234432Y68828D02*
X1234569Y69160D01*
G01X1233079Y69082D02*
G03X1233230Y69324I-648J572D01*
G01X1234054Y68221D02*
G03X1234432Y68828I-1623J1432D01*
G01X1232761Y68855D02*
G03X1233079Y69082I-330J799D01*
G01X1234054Y68221D02*
G03X1234432Y68828I-1623J1432D01*
G01X1214000Y67339D02*
X1212061D01*
G01X1211522Y66039D02*
X1214539D01*
G01X1217425Y70764D02*
X1214000Y67339D01*
G01X1218300Y69800D02*
X1218345Y69844D01*
G01X1214539Y66039D02*
X1218300Y69800D01*
G01X1217706Y71221D02*
G02X1217425Y70764I-1098J360D01*
G01X1218345Y69844D02*
G03X1218942Y70816I-1737J1736D01*
G01X1217845Y71646D02*
X1217706Y71221D01*
G01X1219032Y71091D02*
X1219081Y71241D01*
G01X1218942Y70816D02*
X1219032Y71091D01*
G01X1218325Y72480D02*
G03X1217845Y71646I1759J-1567D01*
G01X1219297Y71616D02*
G02X1219342Y71663I784J-706D01*
G01X1219081Y71241D02*
G02X1219297Y71616I1003J-328D01*
G01X1218519Y72680D02*
X1218422Y72583D01*
G01X1219440Y71760D02*
X1219742Y72062D01*
G01X1218520Y72680D02*
X1218519D01*
G01X1219440Y71760D02*
X1219742Y72062D01*
G01X1218820Y72980D02*
X1218520Y72680D01*
G01X1219742Y72062D02*
X1219858Y72180D01*
G01X1219440Y71760D02*
X1219742Y72062D01*
G01X1219342Y71663D02*
X1219439Y71760D01*
G01X1218937Y73098D02*
X1218820Y72980D01*
G01X1219440Y71760D02*
X1219742Y72062D01*
G01X1219721Y73648D02*
G03X1218937Y73098I1178J-2513D01*
G01X1220273Y72470D02*
G02X1220898Y72610I626J-1331D01*
G01X1219858Y72180D02*
G02X1220273Y72470I1040J-1046D01*
G01X1220897Y73910D02*
G03X1219721Y73648I0J-2771D01*
G01X1220273Y72470D02*
G02X1220898Y72610I626J-1331D01*
G01X1219858Y72180D02*
G02X1220273Y72470I1040J-1046D01*
G01X1222772Y73910D02*
X1220897D01*
G01X1220898Y72610D02*
X1222772D01*
G01X1225748Y71855D02*
G03X1222772Y73910I-2975J-1126D01*
G01Y72610D02*
G02X1224531Y71395I0J-1881D01*
G01X1226122Y69519D02*
G03X1225748Y71855I-5899J254D01*
G01X1224531Y71395D02*
G02X1224823Y69574I-4308J-1625D01*
G01X1225681Y68004D02*
G03X1226122Y69519I-2856J1653D01*
G01X1224555Y68656D02*
G02X1224126Y68140I-1730J1002D01*
G01X1224823Y69574D02*
G02X1224555Y68656I-1998J85D01*
G01X1225554Y52908D02*
G02X1225276Y52486I-2714J1486D01*
G01X1224123Y53159D02*
G03X1224635Y54395I-1236J1236D01*
G01X1225935Y54394D02*
G02X1225554Y52908I-3095J2D01*
G01X1224123Y53159D02*
G03X1224635Y54395I-1236J1236D01*
G01X1225935Y57965D02*
Y54394D01*
G01X1224635Y54395D02*
Y57426D01*
G01X1222700Y61200D02*
X1225935Y57965D01*
G01X1224635Y57426D02*
X1222161Y59900D01*
G01X1211200Y61200D02*
X1222700D01*
G01X1234793Y72471D02*
G03X1233681Y75159I-3802J1D01*
G01X1233493Y72471D02*
G03X1232761Y74239I-2501J0D01*
G01X1234793Y70291D02*
Y72471D01*
G01X1233493Y70291D02*
Y72471D01*
G01X1234569Y69160D02*
G03X1234793Y70291I-2739J1130D01*
G01X1233367Y69656D02*
G03X1233493Y70291I-1537J635D01*
G01X1234432Y68828D02*
X1234569Y69160D01*
G01X1233230Y69324D02*
X1233367Y69656D01*
G01X1234054Y68221D02*
G03X1234432Y68828I-1623J1432D01*
G01X1233079Y69082D02*
G03X1233230Y69324I-648J572D01*
G01X1232761Y68855D02*
G03X1233079Y69082I-330J799D01*
G01X1241440Y107346D02*
X1239961Y110227D01*
G01X1240196Y106922D02*
X1238951Y109346D01*
G01X1242553Y101335D02*
X1241440Y107346D01*
G01X1241229Y101344D02*
X1240196Y106922D01*
G01X1241000Y93571D02*
X1242553Y101335D01*
G01X1239700Y93700D02*
X1241229Y101344D01*
G01X1240196Y106922D02*
X1238951Y109346D01*
G01X1241440Y107346D02*
X1239961Y110227D01*
G01X1241229Y101344D02*
X1240196Y106922D01*
G01X1242553Y101335D02*
X1241440Y107346D01*
G01X1239700Y93700D02*
X1241229Y101344D01*
G01X1241000Y93571D02*
X1242553Y101335D01*
G01X1213823Y75200D02*
X1211049Y77602D01*
G01X1214308Y76500D02*
X1212022Y78480D01*
G01X1230441Y75200D02*
X1213823D01*
G01X1230441Y76500D02*
X1214308D01*
G01X1232761Y74239D02*
G03X1230441Y75200I-2320J-2320D01*
G01X1233681Y75159D02*
G03X1230441Y76500I-3239J-3240D01*
G01X1214308D02*
X1212022Y78480D01*
G01X1213823Y75200D02*
X1211049Y77602D01*
G01X1230441Y76500D02*
X1214308D01*
G01X1230441Y75200D02*
X1213823D01*
G01X1233681Y75159D02*
G03X1230441Y76500I-3239J-3240D01*
G01X1232761Y74239D02*
G03X1230441Y75200I-2320J-2320D01*
G01X1225808Y123492D02*
X1218738Y124995D01*
G01X1226337Y124709D02*
X1219530Y126156D01*
G01X1246119Y109270D02*
X1225808Y123492D01*
G01X1247306Y110026D02*
X1226337Y124709D01*
G01D02*
X1219530Y126156D01*
G01X1225808Y123492D02*
X1218738Y124995D01*
G01X1247306Y110026D02*
X1226337Y124709D01*
G01X1246119Y109270D02*
X1225808Y123492D01*
G01X1230264Y114404D02*
X1220908Y120956D01*
G01X1229754Y113173D02*
X1220398Y119725D01*
G01X1235252Y113525D02*
X1230264Y114404D01*
G01X1234742Y112294D02*
X1229754Y113173D01*
G01X1239961Y110227D02*
X1235252Y113525D01*
G01X1238951Y109346D02*
X1234742Y112294D01*
G01X1229754Y113173D02*
X1220398Y119725D01*
G01X1230264Y114404D02*
X1220908Y120956D01*
G01X1234742Y112294D02*
X1229754Y113173D01*
G01X1235252Y113525D02*
X1230264Y114404D01*
G01X1238951Y109346D02*
X1234742Y112294D01*
G01X1239961Y110227D02*
X1235252Y113525D01*
G01X1220231Y149849D02*
X1220780Y149822D01*
G01X1220225Y149849D02*
X1220231D01*
G01X1220157Y148545D02*
X1220156D01*
G01X1220231Y149849D02*
X1220780Y149822D01*
G01X1220168Y148550D02*
X1220162D01*
G01X1220231Y149849D02*
X1220780Y149822D01*
G01X1220717Y148523D02*
X1220168Y148550D01*
G01X1220780Y149822D02*
X1220781D01*
G01X1220231Y149849D02*
X1220780Y149822D01*
G01X1220225Y149849D02*
X1220231D01*
G01X1220760Y148522D02*
X1220717Y148523D01*
G01X1220231Y149849D02*
X1220780Y149822D01*
G01X1220918Y148522D02*
X1220760D01*
G01X1220231Y149849D02*
X1220780Y149822D01*
G01X1235126Y151541D02*
X1220918Y148522D01*
G01X1220781Y149822D02*
X1235126Y152871D01*
G01X1220780Y149822D02*
X1220781D01*
G01X1220231Y149849D02*
X1220780Y149822D01*
G01X1238883Y150743D02*
X1235126Y151541D01*
G01Y152871D02*
X1239389Y151965D01*
G01X1244288Y147233D02*
X1238883Y150743D01*
G01X1239389Y151965D02*
X1245228Y148173D01*
G01X1248991Y139991D02*
X1244288Y147233D01*
G01X1248991Y139991D02*
X1244288Y147233D01*
G01X1239389Y151965D02*
X1245228Y148173D01*
G01X1244288Y147233D02*
X1238883Y150743D01*
G01X1235126Y152871D02*
X1239389Y151965D01*
G01X1238883Y150743D02*
X1235126Y151541D01*
G01X1220781Y149822D02*
X1235126Y152871D01*
G01Y151541D02*
X1220918Y148522D01*
G01X1220780Y149822D02*
X1220781D01*
G01X1220717Y148523D02*
X1220168Y148550D01*
G01X1235126Y151541D02*
X1220918Y148522D01*
G01X1220231Y149849D02*
X1220780Y149822D01*
G01X1220157Y148545D02*
X1220156D01*
G01X1220168Y148550D02*
X1220162D01*
G01X1220717Y148523D02*
X1220168Y148550D01*
G01X1220760Y148522D02*
X1220717Y148523D01*
G01X1220918Y148522D02*
X1220760D01*
G01X1235126Y151541D02*
X1220918Y148522D01*
G01X1220225Y149849D02*
X1220231D01*
G01X1220717Y148523D02*
X1220168Y148550D01*
G01D02*
X1220162D01*
G01X1220717Y148523D02*
X1220168Y148550D01*
G01X1301884Y827158D02*
X1221452Y712289D01*
G01X1303115Y826648D02*
X1222683Y711779D01*
G01X1296862Y811590D02*
X1225742Y710048D01*
G01X1297796Y810656D02*
X1226972Y709537D01*
G01X1233532Y709272D02*
X1301567Y806434D01*
G01X1234758Y708755D02*
X1302501Y805500D01*
G01X1303115Y826648D02*
X1222683Y711779D01*
G01X1301884Y827158D02*
X1221452Y712289D01*
G01X1297796Y810656D02*
X1226972Y709537D01*
G01X1296862Y811590D02*
X1225742Y710048D01*
G01X1234758Y708755D02*
X1302501Y805500D01*
G01X1233532Y709272D02*
X1301567Y806434D01*
G01X1214920Y741908D02*
X1267500Y817000D01*
G01X1214920Y741908D02*
X1267500Y817000D01*
G01X1213689Y742418D02*
X1227300Y761857D01*
G01X1214920Y741908D02*
X1267500Y817000D01*
G01X1278700Y822480D02*
X1218184Y736056D01*
G01X1280000Y822070D02*
X1219415Y735546D01*
G01X1297119Y828794D02*
X1218700Y716801D01*
G01X1298350Y828284D02*
X1219931Y716291D01*
G01X1214920Y741908D02*
X1267500Y817000D01*
G01X1213689Y742418D02*
X1227300Y761857D01*
G01X1280000Y822070D02*
X1219415Y735546D01*
G01X1278700Y822480D02*
X1218184Y736056D01*
G01X1298350Y828284D02*
X1219931Y716291D01*
G01X1297119Y828794D02*
X1218700Y716801D01*
G01X1240000Y814000D02*
X1211870Y773826D01*
G01X1211813Y753161D02*
X1251269Y809510D01*
G01X1213044Y752651D02*
X1252500Y809000D01*
G01X1239945Y779915D02*
X1266200Y817410D01*
G01X1227300Y761857D02*
X1239945Y779915D01*
G01X1240000Y814000D02*
X1211870Y773826D01*
G01X1213044Y752651D02*
X1252500Y809000D01*
G01X1211813Y753161D02*
X1251269Y809510D01*
G01X1239945Y779915D02*
X1266200Y817410D01*
G01X1227300Y761857D02*
X1239945Y779915D01*
G01X1240783Y825935D02*
X1238769Y814510D01*
G01X1242104Y825935D02*
X1240000Y814000D01*
G01X1242104Y825935D02*
X1240000Y814000D01*
G01X1240783Y825935D02*
X1238769Y814510D01*
G01X1228090Y870539D02*
X1211126Y846314D01*
G01X1229390Y870129D02*
X1212357Y845804D01*
G01X1229390Y870129D02*
X1212357Y845804D01*
G01X1228090Y870539D02*
X1211126Y846314D01*
G01X1214884Y843607D02*
X1221037Y852395D01*
G01X1216115Y843097D02*
X1221971Y851461D01*
G01X1212079Y827700D02*
X1214884Y843607D01*
G01X1213400Y827700D02*
X1216115Y843097D01*
G01X1212702Y824169D02*
X1212079Y827700D01*
G01X1214023Y824169D02*
X1213400Y827700D01*
G01X1240793Y844587D02*
Y826485D01*
G01X1242093Y844473D02*
Y826485D01*
G01X1241381Y847925D02*
X1240793Y844587D01*
G01X1242612Y847415D02*
X1242093Y844473D01*
G01X1253287Y864927D02*
X1241381Y847925D01*
G01X1254587Y864517D02*
X1242612Y847415D01*
G01X1216115Y843097D02*
X1221971Y851461D01*
G01X1214884Y843607D02*
X1221037Y852395D01*
G01X1213400Y827700D02*
X1216115Y843097D01*
G01X1212079Y827700D02*
X1214884Y843607D01*
G01X1214023Y824169D02*
X1213400Y827700D01*
G01X1212702Y824169D02*
X1212079Y827700D01*
G01X1242093Y844473D02*
Y826485D01*
G01X1240793Y844587D02*
Y826485D01*
G01X1242612Y847415D02*
X1242093Y844473D01*
G01X1241381Y847925D02*
X1240793Y844587D01*
G01X1254587Y864517D02*
X1242612Y847415D01*
G01X1253287Y864927D02*
X1241381Y847925D01*
G01X1228090Y873200D02*
Y870539D01*
G01X1229390Y873200D02*
Y870129D01*
G01Y873200D02*
Y870129D01*
G01X1228090Y873200D02*
Y870539D01*
G01X1240689Y869337D02*
Y873200D01*
G01X1241989Y868926D02*
Y873200D01*
G01X1236306Y863085D02*
X1240689Y869337D01*
G01X1237239Y862151D02*
X1241989Y868926D01*
G01X1221037Y852395D02*
X1236306Y863085D01*
G01X1221971Y851461D02*
X1237239Y862151D01*
G01X1241989Y868926D02*
Y873200D01*
G01X1240689Y869337D02*
Y873200D01*
G01X1237239Y862151D02*
X1241989Y868926D01*
G01X1236306Y863085D02*
X1240689Y869337D01*
G01X1221971Y851461D02*
X1237239Y862151D01*
G01X1221037Y852395D02*
X1236306Y863085D01*
G01X1278100Y58861D02*
X1292227Y72987D01*
G01X1276800Y59400D02*
X1291026Y73625D01*
G01X1278100Y58861D02*
X1292227Y72987D01*
G01X1276800Y55001D02*
Y59400D01*
G01X1278100Y54992D02*
Y58861D01*
G01X1276799Y54968D02*
G03X1276800Y55001I-1216J53D01*
G01X1277416Y53274D02*
G03X1278099Y54923I-1833J1725D01*
G01X1276465Y54162D02*
G03X1276799Y54968I-806J806D01*
G01X1278099Y54940D02*
G03X1278100Y54992I-2516J74D01*
G01X1278099Y54923D02*
G03Y54940I-2516J9D01*
G01X1277416Y53274D02*
G03X1278099Y54923I-1833J1725D01*
G01X1277907Y74257D02*
X1289022Y82407D01*
G01X1277410Y73547D02*
X1277907Y74257D01*
G01X1278100Y72265D02*
X1278849Y73335D01*
G01X1276800Y72675D02*
X1277409Y73546D01*
G01X1278100Y72265D02*
X1278849Y73335D01*
G01X1276800Y69959D02*
Y72675D01*
G01X1278100Y69952D02*
Y72265D01*
G01X1276799Y69957D02*
G03X1276800Y69959I-1087J545D01*
G01X1277416Y68234D02*
G03X1278099Y69883I-1833J1725D01*
G01X1276799Y69928D02*
G03Y69957I-1216J14D01*
G01X1277416Y68234D02*
G03X1278099Y69883I-1833J1725D01*
G01X1276465Y69122D02*
G03X1276799Y69928I-806J806D01*
G01X1278099Y69900D02*
G03X1278100Y69952I-2516J74D01*
G01X1278099Y69883D02*
G03Y69900I-2516J8D01*
G01X1277416Y68234D02*
G03X1278099Y69883I-1833J1725D01*
G01X1257212Y73362D02*
G02X1250400Y80174I0J6812D01*
G01X1265328Y73362D02*
X1257212D01*
G01X1268058Y70632D02*
G03X1265328Y73362I-2730J0D01*
G01Y74662D02*
G02X1269358Y70632I0J-4030D01*
G01X1268058Y69648D02*
Y70632D01*
G01X1269358D02*
Y69649D01*
G01X1267921Y68896D02*
G03X1268058Y69648I-1997J752D01*
G01X1269358Y69649D02*
G02X1269106Y68354I-3435J-4D01*
G01X1267901Y68843D02*
G03X1267922Y68896I-1974J813D01*
G01X1269358Y69649D02*
G02X1269106Y68354I-3435J-4D01*
G01X1267766Y68497D02*
G02X1267901Y68843I12281J-4593D01*
G01X1269106Y68354D02*
G03X1268246Y64292I10945J-4439D01*
G01X1244962Y71102D02*
Y93639D01*
G01X1246262Y71216D02*
Y93525D01*
G01X1245757Y66593D02*
X1244962Y71102D01*
G01X1246988Y67103D02*
X1246262Y71216D01*
G01X1249527Y61208D02*
X1245757Y66593D01*
G01X1250397Y62234D02*
X1246988Y67103D01*
G01X1257065Y57600D02*
X1249527Y61208D01*
G01X1257363Y58900D02*
X1250397Y62234D01*
G01X1266142Y57600D02*
X1257065D01*
G01X1266142Y58900D02*
X1257363D01*
G01X1267942Y55800D02*
G03X1266142Y57600I-1800J0D01*
G01X1269242Y55800D02*
G03X1266142Y58900I-3100J0D01*
G01X1267942Y54393D02*
Y55800D01*
G01X1269242Y54394D02*
Y55800D01*
G01X1267774Y53648D02*
G03X1267941Y54394I-1581J746D01*
G01X1268951Y53093D02*
G03X1269242Y54394I-2758J1300D01*
G01X1278100Y58861D02*
X1292227Y72987D01*
G01X1276800Y59400D02*
X1291026Y73625D01*
G01X1278100Y54992D02*
Y58861D01*
G01X1276800Y55001D02*
Y59400D01*
G01X1278099Y54940D02*
G03X1278100Y54992I-2516J74D01*
G01X1276465Y54162D02*
G03X1276799Y54968I-806J806D01*
G01X1278099Y54923D02*
G03Y54940I-2516J9D01*
G01X1276465Y54162D02*
G03X1276799Y54968I-806J806D01*
G01X1277416Y53274D02*
G03X1278099Y54923I-1833J1725D01*
G01X1276799Y54968D02*
G03X1276800Y55001I-1216J53D01*
G01X1276465Y54162D02*
G03X1276799Y54968I-806J806D01*
G01X1277907Y74257D02*
X1289022Y82407D01*
G01X1278100Y72265D02*
X1278849Y73335D01*
G01X1277410Y73547D02*
X1277907Y74257D01*
G01X1276800Y72675D02*
X1277409Y73546D01*
G01X1278100Y69952D02*
Y72265D01*
G01X1276800Y69959D02*
Y72675D01*
G01X1278099Y69900D02*
G03X1278100Y69952I-2516J74D01*
G01X1276465Y69122D02*
G03X1276799Y69928I-806J806D01*
G01X1278099Y69883D02*
G03Y69900I-2516J8D01*
G01X1276465Y69122D02*
G03X1276799Y69928I-806J806D01*
G01X1277416Y68234D02*
G03X1278099Y69883I-1833J1725D01*
G01X1276799Y69957D02*
G03X1276800Y69959I-1087J545D01*
G01X1276799Y69928D02*
G03Y69957I-1216J14D01*
G01X1276465Y69122D02*
G03X1276799Y69928I-806J806D01*
G01X1269106Y68354D02*
G03X1268246Y64292I10945J-4439D01*
G01X1267766Y68497D02*
G02X1267901Y68843I12281J-4593D01*
G01X1269358Y69649D02*
G02X1269106Y68354I-3435J-4D01*
G01X1267921Y68896D02*
G03X1268058Y69648I-1997J752D01*
G01X1267901Y68843D02*
G03X1267922Y68896I-1974J813D01*
G01X1269358Y70632D02*
Y69649D01*
G01X1268058Y69648D02*
Y70632D01*
G01X1265328Y74662D02*
G02X1269358Y70632I0J-4030D01*
G01X1268058D02*
G03X1265328Y73362I-2730J0D01*
G01D02*
X1257212D01*
G01D02*
G02X1250400Y80174I0J6812D01*
G01X1246262Y71216D02*
Y93525D01*
G01X1244962Y71102D02*
Y93639D01*
G01X1246988Y67103D02*
X1246262Y71216D01*
G01X1245757Y66593D02*
X1244962Y71102D01*
G01X1250397Y62234D02*
X1246988Y67103D01*
G01X1249527Y61208D02*
X1245757Y66593D01*
G01X1257363Y58900D02*
X1250397Y62234D01*
G01X1257065Y57600D02*
X1249527Y61208D01*
G01X1266142Y58900D02*
X1257363D01*
G01X1266142Y57600D02*
X1257065D01*
G01X1269242Y55800D02*
G03X1266142Y58900I-3100J0D01*
G01X1267942Y55800D02*
G03X1266142Y57600I-1800J0D01*
G01X1269242Y54394D02*
Y55800D01*
G01X1267942Y54393D02*
Y55800D01*
G01X1268951Y53093D02*
G03X1269242Y54394I-2758J1300D01*
G01X1267774Y53648D02*
G03X1267941Y54394I-1581J746D01*
G01X1252418Y105882D02*
X1251401Y110963D01*
G01X1252701Y111092D02*
X1253744Y105882D01*
G01X1250400Y95795D02*
X1252418Y105882D01*
G01X1253744D02*
X1251700Y95666D01*
G01X1250400Y80174D02*
Y95795D01*
G01X1251700Y95666D02*
Y80174D01*
G01D02*
G03X1257212Y74662I5512J0D01*
G01D02*
X1265328D01*
G01X1246518Y107006D02*
X1246119Y109270D01*
G01X1248239Y104739D02*
X1247306Y110026D01*
G01X1246918Y104739D02*
X1246518Y107005D01*
G01X1248239Y104739D02*
X1247306Y110026D01*
G01X1244962Y93639D02*
X1246918Y104739D01*
G01X1246262Y93525D02*
X1248239Y104739D01*
G01X1257212Y74662D02*
X1265328D01*
G01X1251700Y80174D02*
G03X1257212Y74662I5512J0D01*
G01X1251700Y95666D02*
Y80174D01*
G01X1250400D02*
Y95795D01*
G01X1253744Y105882D02*
X1251700Y95666D01*
G01X1250400Y95795D02*
X1252418Y105882D01*
G01X1252701Y111092D02*
X1253744Y105882D01*
G01X1252418D02*
X1251401Y110963D01*
G01X1248239Y104739D02*
X1247306Y110026D01*
G01X1246518Y107006D02*
X1246119Y109270D01*
G01X1246918Y104739D02*
X1246518Y107005D01*
G01X1246262Y93525D02*
X1248239Y104739D01*
G01X1244962Y93639D02*
X1246918Y104739D01*
G01X1269386Y124681D02*
X1264578Y147298D01*
G01X1270608Y125187D02*
X1265798Y147812D01*
G01X1271479Y121459D02*
X1269386Y124681D01*
G01X1272276Y122619D02*
X1270608Y125187D01*
G01X1283367Y118933D02*
X1271479Y121459D01*
G01X1283873Y120155D02*
X1272276Y122619D01*
G01X1245228Y148173D02*
X1250213Y140497D01*
G01X1249310Y138490D02*
X1248991Y139991D01*
G01X1250213Y140497D02*
X1250959Y136988D01*
G01X1249629D02*
X1249310Y138490D01*
G01X1250213Y140497D02*
X1250959Y136988D01*
G01X1248347Y130958D02*
X1249629Y136988D01*
G01X1250959D02*
X1249672Y130935D01*
G01X1249205Y126081D02*
X1248347Y130958D01*
G01X1249672Y130935D02*
X1250436Y126591D01*
G01X1251434Y122898D02*
X1249205Y126081D01*
G01X1250436Y126591D02*
X1252665Y123408D01*
G01X1252087Y119195D02*
X1251434Y122898D01*
G01X1252665Y123408D02*
X1253410Y119181D01*
G01X1252068Y119101D02*
X1252087Y119195D01*
G01X1253410Y119181D02*
X1253324Y118747D01*
G01X1252062Y119072D02*
X1252068Y119101D01*
G01X1253410Y119181D02*
X1253324Y118747D01*
G01X1251744Y117481D02*
X1252062Y119072D01*
G01X1253324Y118747D02*
X1253019Y117226D01*
G01X1253410Y119181D02*
X1253324Y118747D01*
G01X1251401Y115767D02*
X1251744Y117481D01*
G01X1253019Y117226D02*
X1252701Y115638D01*
G01X1251401Y110963D02*
Y115767D01*
G01X1252701Y115638D02*
Y111092D01*
G01X1270608Y125187D02*
X1265798Y147812D01*
G01X1269386Y124681D02*
X1264578Y147298D01*
G01X1272276Y122619D02*
X1270608Y125187D01*
G01X1271479Y121459D02*
X1269386Y124681D01*
G01X1283873Y120155D02*
X1272276Y122619D01*
G01X1283367Y118933D02*
X1271479Y121459D01*
G01X1252701Y115638D02*
Y111092D01*
G01X1251401Y110963D02*
Y115767D01*
G01X1253019Y117226D02*
X1252701Y115638D01*
G01X1251401Y115767D02*
X1251744Y117481D01*
G01X1253324Y118747D02*
X1253019Y117226D01*
G01X1251744Y117481D02*
X1252062Y119072D01*
G01X1253410Y119181D02*
X1253324Y118747D01*
G01X1252068Y119101D02*
X1252087Y119195D01*
G01X1252062Y119072D02*
X1252068Y119101D01*
G01X1251744Y117481D02*
X1252062Y119072D01*
G01X1252665Y123408D02*
X1253410Y119181D01*
G01X1252087Y119195D02*
X1251434Y122898D01*
G01X1250436Y126591D02*
X1252665Y123408D01*
G01X1251434Y122898D02*
X1249205Y126081D01*
G01X1249672Y130935D02*
X1250436Y126591D01*
G01X1249205Y126081D02*
X1248347Y130958D01*
G01X1250959Y136988D02*
X1249672Y130935D01*
G01X1248347Y130958D02*
X1249629Y136988D01*
G01X1250213Y140497D02*
X1250959Y136988D01*
G01X1249310Y138490D02*
X1248991Y139991D01*
G01X1249629Y136988D02*
X1249310Y138490D01*
G01X1245228Y148173D02*
X1250213Y140497D01*
G01X1262091Y151028D02*
X1255565Y155265D01*
G01X1263025Y151973D02*
X1256052Y156500D01*
G01X1264578Y147298D02*
X1262091Y151028D01*
G01X1265798Y147812D02*
X1263025Y151973D01*
G01D02*
X1256052Y156500D01*
G01X1262091Y151028D02*
X1255565Y155265D01*
G01X1265798Y147812D02*
X1263025Y151973D01*
G01X1264578Y147298D02*
X1262091Y151028D01*
G01X1251269Y809510D02*
X1253794Y823831D01*
G01X1252500Y809000D02*
X1254999Y823170D01*
G01X1251269Y809510D02*
X1253794Y823831D01*
G01X1252500Y809000D02*
X1254999Y823170D01*
G01X1251269Y809510D02*
X1253794Y823831D01*
G01X1252797Y832500D02*
X1256160Y851572D01*
G01X1254118Y832500D02*
X1257391Y851062D01*
G01X1254111Y832461D02*
X1254118Y832500D01*
G01X1253794Y823831D02*
X1252797Y832500D01*
G01X1254981Y824901D02*
X1254111Y832461D01*
G01X1255108Y823792D02*
X1254982Y824895D01*
G01X1254999Y823173D02*
X1255108Y823792D01*
G01X1266200Y840547D02*
X1268251Y852185D01*
G01X1267500Y840433D02*
X1269482Y851675D01*
G01X1266200Y817410D02*
Y840547D01*
G01X1267500Y817000D02*
Y840433D01*
G01X1254118Y832500D02*
X1257391Y851062D01*
G01X1252797Y832500D02*
X1256160Y851572D01*
G01X1254111Y832461D02*
X1254118Y832500D01*
G01X1252797D02*
X1256160Y851572D01*
G01X1254981Y824901D02*
X1254111Y832461D01*
G01X1253794Y823831D02*
X1252797Y832500D01*
G01X1255108Y823792D02*
X1254982Y824895D01*
G01X1253794Y823831D02*
X1252797Y832500D01*
G01X1254999Y823173D02*
X1255108Y823792D01*
G01X1267500Y840433D02*
X1269482Y851675D01*
G01X1266200Y840547D02*
X1268251Y852185D01*
G01X1267500Y817000D02*
Y840433D01*
G01X1266200Y817410D02*
Y840547D01*
G01X1253287Y873200D02*
Y864927D01*
G01X1254587Y873200D02*
Y864517D01*
G01X1265886Y865462D02*
Y873200D01*
G01X1267186Y865052D02*
Y873200D01*
G01X1256160Y851572D02*
X1265886Y865462D01*
G01X1257391Y851062D02*
X1267186Y865052D01*
G01X1277470Y865354D02*
X1278484Y868889D01*
G01X1268251Y852185D02*
X1277470Y865354D01*
G01X1269482Y851675D02*
X1278660Y864787D01*
G01X1254587Y873200D02*
Y864517D01*
G01X1253287Y873200D02*
Y864927D01*
G01X1267186Y865052D02*
Y873200D01*
G01X1265886Y865462D02*
Y873200D01*
G01X1257391Y851062D02*
X1267186Y865052D01*
G01X1256160Y851572D02*
X1265886Y865462D01*
G01X1277470Y865354D02*
X1278484Y868889D01*
G01X1269482Y851675D02*
X1278660Y864787D01*
G01X1268251Y852185D02*
X1277470Y865354D01*
G01X1291035Y73634D02*
X1296732Y100439D01*
G01X1292227Y72987D02*
X1298062Y100439D01*
G01X1291026Y73634D02*
X1291035D01*
G01X1278849Y73335D02*
X1290191Y81652D01*
G01X1292227Y72987D02*
X1298062Y100439D01*
G01X1291035Y73634D02*
X1296732Y100439D01*
G01X1291026Y73634D02*
X1291035D01*
G01X1278849Y73335D02*
X1290191Y81652D01*
G01X1296732Y100439D02*
X1294929Y108930D01*
G01X1298062Y100439D02*
X1296259Y108930D01*
G01X1292091Y96851D02*
X1288497Y114134D01*
G01X1293420Y96848D02*
X1289721Y114639D01*
G01X1289022Y82407D02*
X1292091Y96851D01*
G01X1290191Y81652D02*
X1293420Y96848D01*
G01X1298062Y100439D02*
X1296259Y108930D01*
G01X1296732Y100439D02*
X1294929Y108930D01*
G01X1293420Y96848D02*
X1289721Y114639D01*
G01X1292091Y96851D02*
X1288497Y114134D01*
G01X1290191Y81652D02*
X1293420Y96848D01*
G01X1289022Y82407D02*
X1292091Y96851D01*
G01X1299407Y141762D02*
X1280433Y154086D01*
G01X1300655Y135883D02*
X1299407Y141762D01*
G01X1301985Y135883D02*
X1300567Y142559D01*
G01X1294929Y108930D02*
X1300655Y135883D01*
G01X1296259Y108930D02*
X1301985Y135883D01*
G01X1286845Y116672D02*
X1283367Y118933D01*
G01X1287785Y117613D02*
X1283873Y120155D01*
G01X1288497Y114134D02*
X1286845Y116672D01*
G01X1289721Y114639D02*
X1287785Y117613D01*
G01X1299407Y141762D02*
X1280433Y154086D01*
G01X1301985Y135883D02*
X1300567Y142559D01*
G01X1300655Y135883D02*
X1299407Y141762D01*
G01X1296259Y108930D02*
X1301985Y135883D01*
G01X1294929Y108930D02*
X1300655Y135883D01*
G01X1287785Y117613D02*
X1283873Y120155D01*
G01X1286845Y116672D02*
X1283367Y118933D01*
G01X1289721Y114639D02*
X1287785Y117613D01*
G01X1288497Y114134D02*
X1286845Y116672D01*
G01X1300567Y142559D02*
X1280939Y155308D01*
G01X1300567Y142559D02*
X1280939Y155308D01*
G01X1314241Y823758D02*
X1296862Y811590D01*
G01X1315080Y822758D02*
X1297796Y810656D01*
G01X1301567Y806434D02*
X1312877Y814353D01*
G01X1302501Y805500D02*
X1313387Y813122D01*
G01X1315080Y822758D02*
X1297796Y810656D01*
G01X1314241Y823758D02*
X1296862Y811590D01*
G01X1302501Y805500D02*
X1313387Y813122D01*
G01X1301567Y806434D02*
X1312877Y814353D01*
G01X1278700Y841414D02*
Y822480D01*
G01X1280000Y841300D02*
Y822070D01*
G01X1280147Y849625D02*
X1278700Y841414D01*
G01X1281378Y849115D02*
X1280000Y841300D01*
G01X1284700Y856127D02*
X1280147Y849625D01*
G01X1285634Y855193D02*
X1281378Y849115D01*
G01X1303681Y866009D02*
X1297119Y828794D01*
G01X1304981Y865892D02*
X1298350Y828284D01*
G01X1280000Y841300D02*
Y822070D01*
G01X1278700Y841414D02*
Y822480D01*
G01X1281378Y849115D02*
X1280000Y841300D01*
G01X1280147Y849625D02*
X1278700Y841414D01*
G01X1285634Y855193D02*
X1281378Y849115D01*
G01X1284700Y856127D02*
X1280147Y849625D01*
G01X1304981Y865892D02*
X1298350Y828284D01*
G01X1303681Y866009D02*
X1297119Y828794D01*
G01X1304961Y844616D02*
X1301884Y827158D01*
G01X1306192Y844106D02*
X1303115Y826648D01*
G01X1315662Y859899D02*
X1304961Y844616D01*
G01X1316893Y859389D02*
X1306192Y844106D01*
G01D02*
X1303115Y826648D01*
G01X1304961Y844616D02*
X1301884Y827158D01*
G01X1316893Y859389D02*
X1306192Y844106D01*
G01X1315662Y859899D02*
X1304961Y844616D01*
G01X1278484Y868889D02*
Y873200D01*
G01X1279784Y868706D02*
Y873200D01*
G01X1278660Y864787D02*
X1279784Y868706D01*
G01X1288566Y858834D02*
X1284700Y856127D01*
G01X1289500Y857900D02*
X1285634Y855193D01*
G01X1291083Y862428D02*
X1288566Y858834D01*
G01X1292383Y862017D02*
X1289500Y857900D01*
G01X1291083Y873200D02*
Y862428D01*
G01X1292383Y873200D02*
Y862017D01*
G01X1303681Y873200D02*
Y866009D01*
G01X1304981Y873200D02*
Y865892D01*
G01X1279784Y868706D02*
Y873200D01*
G01X1278484Y868889D02*
Y873200D01*
G01X1278660Y864787D02*
X1279784Y868706D01*
G01X1289500Y857900D02*
X1285634Y855193D01*
G01X1288566Y858834D02*
X1284700Y856127D01*
G01X1292383Y862017D02*
X1289500Y857900D01*
G01X1291083Y862428D02*
X1288566Y858834D01*
G01X1292383Y873200D02*
Y862017D01*
G01X1291083Y873200D02*
Y862428D01*
G01X1304981Y873200D02*
Y865892D01*
G01X1303681Y873200D02*
Y866009D01*
G01X1317290Y815131D02*
X1327267Y822116D01*
G01X1317800Y813900D02*
X1328201Y821182D01*
G01X1312877Y814353D02*
X1317290Y815131D01*
G01X1313387Y813122D02*
X1317800Y813900D01*
G01D02*
X1328201Y821182D01*
G01X1317290Y815131D02*
X1327267Y822116D01*
G01X1313387Y813122D02*
X1317800Y813900D01*
G01X1312877Y814353D02*
X1317290Y815131D01*
G01X1316300Y825817D02*
X1314241Y823758D01*
G01X1317600Y825278D02*
X1315080Y822758D01*
G01X1316300Y842645D02*
Y825817D01*
G01X1317600Y842531D02*
Y825278D01*
G01X1316769Y845310D02*
X1316300Y842645D01*
G01X1318000Y844800D02*
X1317600Y842531D01*
G01X1328878Y862602D02*
X1316769Y845310D01*
G01X1330178Y862191D02*
X1318000Y844800D01*
G01X1328878Y841436D02*
X1331053Y853777D01*
G01X1330178Y841322D02*
X1332284Y853268D01*
G01X1328878Y824415D02*
Y841436D01*
G01X1330178Y824005D02*
Y841322D01*
G01X1327267Y822116D02*
X1328878Y824415D01*
G01X1328201Y821182D02*
X1330178Y824005D01*
G01X1317600Y825278D02*
X1315080Y822758D01*
G01X1316300Y825817D02*
X1314241Y823758D01*
G01X1317600Y842531D02*
Y825278D01*
G01X1316300Y842645D02*
Y825817D01*
G01X1318000Y844800D02*
X1317600Y842531D01*
G01X1316769Y845310D02*
X1316300Y842645D01*
G01X1330178Y862191D02*
X1318000Y844800D01*
G01X1328878Y862602D02*
X1316769Y845310D01*
G01X1330178Y841322D02*
X1332284Y853268D01*
G01X1328878Y841436D02*
X1331053Y853777D01*
G01X1330178Y824005D02*
Y841322D01*
G01X1328878Y824415D02*
Y841436D01*
G01X1328201Y821182D02*
X1330178Y824005D01*
G01X1327267Y822116D02*
X1328878Y824415D01*
G01X1316279Y863398D02*
X1315662Y859899D01*
G01X1317579Y863281D02*
X1316893Y859389D01*
G01X1316279Y873200D02*
Y863398D01*
G01X1317579Y873200D02*
Y863281D01*
G01X1328878Y873200D02*
Y862602D01*
G01X1330178Y873200D02*
Y862191D01*
G01X1341476Y868683D02*
Y873200D01*
G01X1342776Y868273D02*
Y873200D01*
G01X1331053Y853777D02*
X1341476Y868683D01*
G01X1332284Y853268D02*
X1342776Y868273D01*
G01X1317579Y863281D02*
X1316893Y859389D01*
G01X1316279Y863398D02*
X1315662Y859899D01*
G01X1317579Y873200D02*
Y863281D01*
G01X1316279Y873200D02*
Y863398D01*
G01X1330178Y873200D02*
Y862191D01*
G01X1328878Y873200D02*
Y862602D01*
G01X1342776Y868273D02*
Y873200D01*
G01X1341476Y868683D02*
Y873200D01*
G01X1332284Y853268D02*
X1342776Y868273D01*
G01X1331053Y853777D02*
X1341476Y868683D01*
M02*
